FILE_TYPE = MACRO_DRAWING;
SET COLOR_WIRE YELLOW;
SET COLOR_PROP MONO;
SET COLOR_DOT WHITE;
SET COLOR_ARC YELLOW;
SET COLOR_BODY GREEN;
SET COLOR_NOTE MONO;
SET PROP_DISPLAY VALUE;
SET PAGE_NUMBER P74;
FORCEADD GND..1
(-7625 475);
FORCEPROP 3 LASTPIN (-7625 525) SIG_NAME GND\g
J 0
(-7615 535);
DISPLAY 0.659574 (-7615 535);
PAINT MONO (-7615 535);
DISPLAY INVISIBLE (-7615 535);
FORCEPROP 1 LAST VOLTAGE 0.0V
J 0
(-7670 432);
DISPLAY 0.340426 (-7670 432);
PAINT SKYBLUE (-7670 432);
DISPLAY INVISIBLE (-7670 432);
FORCEPROP 1 LAST SIZE 1B
J 0
(-7550 425);
DISPLAY 1.170213 (-7550 425);
PAINT AQUA (-7550 425);
DISPLAY INVISIBLE (-7550 425);
FORCEPROP 2 LAST CDS_LIB mstr_symbols
J 0
(-7625 475);
PAINT ORANGE (-7625 475);
DISPLAY INVISIBLE (-7625 475);
FORCEPROP 1 LAST BODY_TYPE PLUMBING
J 0
(-7670 432);
DISPLAY 0.340426 (-7670 432);
PAINT GREEN (-7670 432);
DISPLAY INVISIBLE (-7670 432);
FORCEPROP 1 LAST PATH I1
J 0
(-7550 475);
DISPLAY 1.170213 (-7550 475);
PAINT AQUA (-7550 475);
DISPLAY INVISIBLE (-7550 475);
FORCEPROP 1 LAST HDL_POWER GND
J 0
(-7625 625);
DISPLAY 1.170213 (-7625 625);
PAINT GREEN (-7625 625);
DISPLAY INVISIBLE (-7625 625);
FORCEADD GND..1
(-2425 500);
FORCEPROP 3 LASTPIN (-2425 550) SIG_NAME GND\g
J 0
(-2415 560);
DISPLAY 0.659574 (-2415 560);
PAINT MONO (-2415 560);
DISPLAY INVISIBLE (-2415 560);
FORCEPROP 1 LAST VOLTAGE 0.0V
J 0
(-2470 457);
DISPLAY 0.340426 (-2470 457);
PAINT SKYBLUE (-2470 457);
DISPLAY INVISIBLE (-2470 457);
FORCEPROP 2 LAST CDS_LIB mstr_symbols
J 0
(-2425 500);
PAINT ORANGE (-2425 500);
DISPLAY INVISIBLE (-2425 500);
FORCEPROP 1 LAST SIZE 1B
J 0
(-2350 450);
DISPLAY 1.170213 (-2350 450);
PAINT AQUA (-2350 450);
DISPLAY INVISIBLE (-2350 450);
FORCEPROP 1 LAST BODY_TYPE PLUMBING
J 0
(-2470 457);
DISPLAY 0.340426 (-2470 457);
PAINT GREEN (-2470 457);
DISPLAY INVISIBLE (-2470 457);
FORCEPROP 1 LAST PATH I11
J 0
(-2350 500);
DISPLAY 0.872340 (-2350 500);
PAINT AQUA (-2350 500);
DISPLAY INVISIBLE (-2350 500);
FORCEPROP 1 LAST HDL_POWER GND
J 0
(-2425 650);
DISPLAY 1.170213 (-2425 650);
PAINT GREEN (-2425 650);
DISPLAY INVISIBLE (-2425 650);
FORCEADD GND..1
(-2025 475);
FORCEPROP 3 LASTPIN (-2025 525) SIG_NAME GND\g
J 0
(-2015 535);
DISPLAY 0.659574 (-2015 535);
PAINT MONO (-2015 535);
DISPLAY INVISIBLE (-2015 535);
FORCEPROP 1 LAST VOLTAGE 0.0V
J 0
(-2070 432);
DISPLAY 0.340426 (-2070 432);
PAINT SKYBLUE (-2070 432);
DISPLAY INVISIBLE (-2070 432);
FORCEPROP 1 LAST SIZE 1B
J 0
(-1950 425);
DISPLAY 1.170213 (-1950 425);
PAINT AQUA (-1950 425);
DISPLAY INVISIBLE (-1950 425);
FORCEPROP 2 LAST CDS_LIB mstr_symbols
J 0
(-2025 475);
PAINT ORANGE (-2025 475);
DISPLAY INVISIBLE (-2025 475);
FORCEPROP 1 LAST BODY_TYPE PLUMBING
J 0
(-2070 432);
DISPLAY 0.340426 (-2070 432);
PAINT GREEN (-2070 432);
DISPLAY INVISIBLE (-2070 432);
FORCEPROP 1 LAST PATH I12
J 0
(-1950 475);
DISPLAY 0.872340 (-1950 475);
PAINT AQUA (-1950 475);
DISPLAY INVISIBLE (-1950 475);
FORCEPROP 1 LAST HDL_POWER GND
J 0
(-2025 625);
DISPLAY 1.170213 (-2025 625);
PAINT GREEN (-2025 625);
DISPLAY INVISIBLE (-2025 625);
FORCEADD GND..1
(-500 475);
FORCEPROP 3 LASTPIN (-500 525) SIG_NAME GND\g
J 0
(-490 535);
DISPLAY 0.659574 (-490 535);
PAINT MONO (-490 535);
DISPLAY INVISIBLE (-490 535);
FORCEPROP 1 LAST VOLTAGE 0.0V
J 0
(-545 432);
DISPLAY 0.340426 (-545 432);
PAINT SKYBLUE (-545 432);
DISPLAY INVISIBLE (-545 432);
FORCEPROP 1 LAST SIZE 1B
J 0
(-425 425);
DISPLAY 1.170213 (-425 425);
PAINT AQUA (-425 425);
DISPLAY INVISIBLE (-425 425);
FORCEPROP 2 LAST CDS_LIB mstr_symbols
J 0
(-500 475);
PAINT ORANGE (-500 475);
DISPLAY INVISIBLE (-500 475);
FORCEPROP 1 LAST BODY_TYPE PLUMBING
J 0
(-545 432);
DISPLAY 0.340426 (-545 432);
PAINT GREEN (-545 432);
DISPLAY INVISIBLE (-545 432);
FORCEPROP 1 LAST PATH I14
J 0
(-425 475);
DISPLAY 0.872340 (-425 475);
PAINT AQUA (-425 475);
DISPLAY INVISIBLE (-425 475);
FORCEPROP 1 LAST HDL_POWER GND
J 0
(-500 625);
DISPLAY 1.170213 (-500 625);
PAINT GREEN (-500 625);
DISPLAY INVISIBLE (-500 625);
FORCEADD SKX_EXT_B..23
(-6875 2600);
FORCEPROP 1 LAST LOCATION U2D1
J 0
(-7425 4850);
DISPLAY 0.617021 (-7425 4850);
PAINT AQUA (-7425 4850);
FORCEPROP 1 LAST PART_NUMBER TBD
J 0
(-7425 450);
DISPLAY 0.617021 (-7425 450);
PAINT BLUE (-7425 450);
FORCEPROP 1 LAST MATERIAL IC
J 0
(-7425 4800);
DISPLAY 0.617021 (-7425 4800);
PAINT SKYBLUE (-7425 4800);
FORCEPROP 2 LASTPIN (-7475 4550) $PN A42
J 2
(-7485 4560);
DISPLAY 0.617021 (-7485 4560);
PAINT ORANGE (-7485 4560);
FORCEPROP 2 LASTPIN (-7475 4500) $PN B43
J 2
(-7485 4510);
DISPLAY 0.617021 (-7485 4510);
PAINT ORANGE (-7485 4510);
FORCEPROP 2 LASTPIN (-7475 4450) $PN B5
J 2
(-7485 4460);
DISPLAY 0.617021 (-7485 4460);
PAINT ORANGE (-7485 4460);
FORCEPROP 2 LASTPIN (-7475 4400) $PN B79
J 2
(-7485 4410);
DISPLAY 0.617021 (-7485 4410);
PAINT ORANGE (-7485 4410);
FORCEPROP 2 LASTPIN (-7475 4350) $PN C4
J 2
(-7485 4360);
DISPLAY 0.617021 (-7485 4360);
PAINT ORANGE (-7485 4360);
FORCEPROP 2 LASTPIN (-7475 4250) $PN D3
J 2
(-7485 4260);
DISPLAY 0.617021 (-7485 4260);
PAINT ORANGE (-7485 4260);
FORCEPROP 2 LASTPIN (-7475 4200) $PN D81
J 2
(-7485 4210);
DISPLAY 0.617021 (-7485 4210);
PAINT ORANGE (-7485 4210);
FORCEPROP 2 LASTPIN (-7475 4150) $PN E82
J 2
(-7485 4160);
DISPLAY 0.617021 (-7485 4160);
PAINT ORANGE (-7485 4160);
FORCEPROP 2 LASTPIN (-7475 4100) $PN J86
J 2
(-7485 4110);
DISPLAY 0.617021 (-7485 4110);
PAINT ORANGE (-7485 4110);
FORCEPROP 2 LASTPIN (-7475 4050) $PN DY85
J 2
(-7485 4060);
DISPLAY 0.617021 (-7485 4060);
PAINT ORANGE (-7485 4060);
FORCEPROP 2 LASTPIN (-7475 4000) $PN EA84
J 2
(-7485 4010);
DISPLAY 0.617021 (-7485 4010);
PAINT ORANGE (-7485 4010);
FORCEPROP 2 LASTPIN (-7475 3950) $PN EB83
J 2
(-7485 3960);
DISPLAY 0.617021 (-7485 3960);
PAINT ORANGE (-7485 3960);
FORCEPROP 2 LASTPIN (-7475 3900) $PN DW2
J 2
(-7485 3910);
DISPLAY 0.617021 (-7485 3910);
PAINT ORANGE (-7485 3910);
FORCEPROP 2 LASTPIN (-7475 3850) $PN EC42
J 2
(-7485 3860);
DISPLAY 0.617021 (-7485 3860);
PAINT ORANGE (-7485 3860);
FORCEPROP 2 LASTPIN (-7475 3800) $PN EC6
J 2
(-7485 3810);
DISPLAY 0.617021 (-7485 3810);
PAINT ORANGE (-7485 3810);
FORCEPROP 2 LASTPIN (-7475 3750) $PN EC82
J 2
(-7485 3760);
DISPLAY 0.617021 (-7485 3760);
PAINT ORANGE (-7485 3760);
FORCEPROP 2 LASTPIN (-7475 3700) $PN ED41
J 2
(-7485 3710);
DISPLAY 0.617021 (-7485 3710);
PAINT ORANGE (-7485 3710);
FORCEPROP 2 LASTPIN (-7475 3650) $PN ED7
J 2
(-7485 3660);
DISPLAY 0.617021 (-7485 3660);
PAINT ORANGE (-7485 3660);
FORCEPROP 2 LASTPIN (-7475 3600) $PN ED81
J 2
(-7485 3610);
DISPLAY 0.617021 (-7485 3610);
PAINT ORANGE (-7485 3610);
FORCEPROP 2 LASTPIN (-7475 3550) $PN EE40
J 2
(-7485 3560);
DISPLAY 0.617021 (-7485 3560);
PAINT ORANGE (-7485 3560);
FORCEPROP 2 LASTPIN (-7475 3500) $PN EE8
J 2
(-7485 3510);
DISPLAY 0.617021 (-7485 3510);
PAINT ORANGE (-7485 3510);
FORCEPROP 2 LASTPIN (-7475 3450) $PN EE80
J 2
(-7485 3460);
DISPLAY 0.617021 (-7485 3460);
PAINT ORANGE (-7485 3460);
FORCEPROP 2 LASTPIN (-7475 3400) $PN ED69
J 2
(-7485 3410);
DISPLAY 0.617021 (-7485 3410);
PAINT ORANGE (-7485 3410);
FORCEPROP 2 LASTPIN (-7475 3350) $PN E66
J 2
(-7485 3360);
DISPLAY 0.617021 (-7485 3360);
PAINT ORANGE (-7485 3360);
FORCEPROP 2 LASTPIN (-7475 3300) $PN V11
J 2
(-7485 3310);
DISPLAY 0.617021 (-7485 3310);
PAINT ORANGE (-7485 3310);
FORCEPROP 2 LASTPIN (-7475 3250) $PN L8
J 2
(-7485 3260);
DISPLAY 0.617021 (-7485 3260);
PAINT ORANGE (-7485 3260);
FORCEPROP 2 LASTPIN (-7475 3200) $PN EA14
J 2
(-7485 3210);
DISPLAY 0.617021 (-7485 3210);
PAINT ORANGE (-7485 3210);
FORCEPROP 2 LASTPIN (-7475 3150) $PN DY63
J 2
(-7485 3160);
DISPLAY 0.617021 (-7485 3160);
PAINT ORANGE (-7485 3160);
FORCEPROP 2 LASTPIN (-7475 3100) $PN DY61
J 2
(-7485 3110);
DISPLAY 0.617021 (-7485 3110);
PAINT ORANGE (-7485 3110);
FORCEPROP 2 LASTPIN (-7475 3050) $PN DY59
J 2
(-7485 3060);
DISPLAY 0.617021 (-7485 3060);
PAINT ORANGE (-7485 3060);
FORCEPROP 2 LASTPIN (-7475 3000) $PN DY57
J 2
(-7485 3010);
DISPLAY 0.617021 (-7485 3010);
PAINT ORANGE (-7485 3010);
FORCEPROP 2 LASTPIN (-7475 2950) $PN DY55
J 2
(-7485 2960);
DISPLAY 0.617021 (-7485 2960);
PAINT ORANGE (-7485 2960);
FORCEPROP 2 LASTPIN (-7475 2900) $PN DY53
J 2
(-7485 2910);
DISPLAY 0.617021 (-7485 2910);
PAINT ORANGE (-7485 2910);
FORCEPROP 2 LASTPIN (-7475 2850) $PN DY51
J 2
(-7485 2860);
DISPLAY 0.617021 (-7485 2860);
PAINT ORANGE (-7485 2860);
FORCEPROP 2 LASTPIN (-7475 2800) $PN DY49
J 2
(-7485 2810);
DISPLAY 0.617021 (-7485 2810);
PAINT ORANGE (-7485 2810);
FORCEPROP 2 LASTPIN (-7475 2750) $PN DY47
J 2
(-7485 2760);
DISPLAY 0.617021 (-7485 2760);
PAINT ORANGE (-7485 2760);
FORCEPROP 2 LASTPIN (-7475 2700) $PN DY45
J 2
(-7485 2710);
DISPLAY 0.617021 (-7485 2710);
PAINT ORANGE (-7485 2710);
FORCEPROP 2 LASTPIN (-7475 2650) $PN DV19
J 2
(-7485 2660);
DISPLAY 0.617021 (-7485 2660);
PAINT ORANGE (-7485 2660);
FORCEPROP 2 LASTPIN (-7475 2600) $PN DP9
J 2
(-7485 2610);
DISPLAY 0.617021 (-7485 2610);
PAINT ORANGE (-7485 2610);
FORCEPROP 2 LASTPIN (-7475 2550) $PN DP63
J 2
(-7485 2560);
DISPLAY 0.617021 (-7485 2560);
PAINT ORANGE (-7485 2560);
FORCEPROP 2 LASTPIN (-7475 2500) $PN DP61
J 2
(-7485 2510);
DISPLAY 0.617021 (-7485 2510);
PAINT ORANGE (-7485 2510);
FORCEPROP 2 LASTPIN (-7475 2450) $PN DP59
J 2
(-7485 2460);
DISPLAY 0.617021 (-7485 2460);
PAINT ORANGE (-7485 2460);
FORCEPROP 2 LASTPIN (-7475 2400) $PN DP57
J 2
(-7485 2410);
DISPLAY 0.617021 (-7485 2410);
PAINT ORANGE (-7485 2410);
FORCEPROP 2 LASTPIN (-7475 2350) $PN DP55
J 2
(-7485 2360);
DISPLAY 0.617021 (-7485 2360);
PAINT ORANGE (-7485 2360);
FORCEPROP 2 LASTPIN (-7475 2300) $PN DP53
J 2
(-7485 2310);
DISPLAY 0.617021 (-7485 2310);
PAINT ORANGE (-7485 2310);
FORCEPROP 2 LASTPIN (-7475 2250) $PN DP51
J 2
(-7485 2260);
DISPLAY 0.617021 (-7485 2260);
PAINT ORANGE (-7485 2260);
FORCEPROP 2 LASTPIN (-7475 2200) $PN DP49
J 2
(-7485 2210);
DISPLAY 0.617021 (-7485 2210);
PAINT ORANGE (-7485 2210);
FORCEPROP 2 LASTPIN (-7475 2150) $PN DP47
J 2
(-7485 2160);
DISPLAY 0.617021 (-7485 2160);
PAINT ORANGE (-7485 2160);
FORCEPROP 2 LASTPIN (-7475 2100) $PN DP45
J 2
(-7485 2110);
DISPLAY 0.617021 (-7485 2110);
PAINT ORANGE (-7485 2110);
FORCEPROP 2 LASTPIN (-7475 2050) $PN DN18
J 2
(-7485 2060);
DISPLAY 0.617021 (-7485 2060);
PAINT ORANGE (-7485 2060);
FORCEPROP 2 LASTPIN (-7475 2000) $PN DL8
J 2
(-7485 2010);
DISPLAY 0.617021 (-7485 2010);
PAINT ORANGE (-7485 2010);
FORCEPROP 2 LASTPIN (-7475 1950) $PN DE62
J 2
(-7485 1960);
DISPLAY 0.617021 (-7485 1960);
PAINT ORANGE (-7485 1960);
FORCEPROP 2 LASTPIN (-7475 1900) $PN DE60
J 2
(-7485 1910);
DISPLAY 0.617021 (-7485 1910);
PAINT ORANGE (-7485 1910);
FORCEPROP 2 LASTPIN (-7475 1850) $PN DE58
J 2
(-7485 1860);
DISPLAY 0.617021 (-7485 1860);
PAINT ORANGE (-7485 1860);
FORCEPROP 2 LASTPIN (-7475 1800) $PN DE56
J 2
(-7485 1810);
DISPLAY 0.617021 (-7485 1810);
PAINT ORANGE (-7485 1810);
FORCEPROP 2 LASTPIN (-7475 1750) $PN DE54
J 2
(-7485 1760);
DISPLAY 0.617021 (-7485 1760);
PAINT ORANGE (-7485 1760);
FORCEPROP 2 LASTPIN (-7475 1700) $PN DE52
J 2
(-7485 1710);
DISPLAY 0.617021 (-7485 1710);
PAINT ORANGE (-7485 1710);
FORCEPROP 2 LASTPIN (-7475 1650) $PN DE50
J 2
(-7485 1660);
DISPLAY 0.617021 (-7485 1660);
PAINT ORANGE (-7485 1660);
FORCEPROP 2 LASTPIN (-7475 1600) $PN DE48
J 2
(-7485 1610);
DISPLAY 0.617021 (-7485 1610);
PAINT ORANGE (-7485 1610);
FORCEPROP 2 LASTPIN (-7475 1550) $PN CW6
J 2
(-7485 1560);
DISPLAY 0.617021 (-7485 1560);
PAINT ORANGE (-7485 1560);
FORCEPROP 2 LASTPIN (-7475 1500) $PN CG6
J 2
(-7485 1510);
DISPLAY 0.617021 (-7485 1510);
PAINT ORANGE (-7485 1510);
FORCEPROP 2 LASTPIN (-7475 1450) $PN AR6
J 2
(-7485 1460);
DISPLAY 0.617021 (-7485 1460);
PAINT ORANGE (-7485 1460);
FORCEPROP 2 LASTPIN (-7475 1400) $PN AJ4
J 2
(-7485 1410);
DISPLAY 0.617021 (-7485 1410);
PAINT ORANGE (-7485 1410);
FORCEPROP 2 LASTPIN (-7475 1350) $PN AC62
J 2
(-7485 1360);
DISPLAY 0.617021 (-7485 1360);
PAINT ORANGE (-7485 1360);
FORCEPROP 2 LASTPIN (-7475 1300) $PN AC60
J 2
(-7485 1310);
DISPLAY 0.617021 (-7485 1310);
PAINT ORANGE (-7485 1310);
FORCEPROP 2 LASTPIN (-7475 1250) $PN AC58
J 2
(-7485 1260);
DISPLAY 0.617021 (-7485 1260);
PAINT ORANGE (-7485 1260);
FORCEPROP 2 LASTPIN (-7475 1200) $PN A26
J 2
(-7485 1210);
DISPLAY 0.617021 (-7485 1210);
PAINT ORANGE (-7485 1210);
FORCEPROP 2 LASTPIN (-7475 1150) $PN A30
J 2
(-7485 1160);
DISPLAY 0.617021 (-7485 1160);
PAINT ORANGE (-7485 1160);
FORCEPROP 2 LASTPIN (-7475 1100) $PN A32
J 2
(-7485 1110);
DISPLAY 0.617021 (-7485 1110);
PAINT ORANGE (-7485 1110);
FORCEPROP 2 LASTPIN (-7475 1050) $PN A36
J 2
(-7485 1060);
DISPLAY 0.617021 (-7485 1060);
PAINT ORANGE (-7485 1060);
FORCEPROP 2 LASTPIN (-7475 1000) $PN A38
J 2
(-7485 1010);
DISPLAY 0.617021 (-7485 1010);
PAINT ORANGE (-7485 1010);
FORCEPROP 2 LASTPIN (-7475 950) $PN B25
J 2
(-7485 960);
DISPLAY 0.617021 (-7485 960);
PAINT ORANGE (-7485 960);
FORCEPROP 2 LASTPIN (-7475 900) $PN B31
J 2
(-7485 910);
DISPLAY 0.617021 (-7485 910);
PAINT ORANGE (-7485 910);
FORCEPROP 2 LASTPIN (-7475 850) $PN B37
J 2
(-7485 860);
DISPLAY 0.617021 (-7485 860);
PAINT ORANGE (-7485 860);
FORCEPROP 2 LASTPIN (-7475 800) $PN B71
J 2
(-7485 810);
DISPLAY 0.617021 (-7485 810);
PAINT ORANGE (-7485 810);
FORCEPROP 2 LASTPIN (-7475 750) $PN B75
J 2
(-7485 760);
DISPLAY 0.617021 (-7485 760);
PAINT ORANGE (-7485 760);
FORCEPROP 2 LASTPIN (-7475 700) $PN C8
J 2
(-7485 710);
DISPLAY 0.617021 (-7485 710);
PAINT ORANGE (-7485 710);
FORCEPROP 2 LASTPIN (-7475 650) $PN C10
J 2
(-7485 660);
DISPLAY 0.617021 (-7485 660);
PAINT ORANGE (-7485 660);
FORCEPROP 2 LASTPIN (-6275 4600) $PN C12
J 0
(-6265 4610);
DISPLAY 0.617021 (-6265 4610);
PAINT ORANGE (-6265 4610);
FORCEPROP 2 LASTPIN (-6275 4550) $PN C14
J 0
(-6265 4560);
DISPLAY 0.617021 (-6265 4560);
PAINT ORANGE (-6265 4560);
FORCEPROP 2 LASTPIN (-6275 4500) $PN C16
J 0
(-6265 4510);
DISPLAY 0.617021 (-6265 4510);
PAINT ORANGE (-6265 4510);
FORCEPROP 2 LASTPIN (-6275 4450) $PN C76
J 0
(-6265 4460);
DISPLAY 0.617021 (-6265 4460);
PAINT ORANGE (-6265 4460);
FORCEPROP 2 LASTPIN (-6275 4400) $PN C78
J 0
(-6265 4410);
DISPLAY 0.617021 (-6265 4410);
PAINT ORANGE (-6265 4410);
FORCEPROP 2 LASTPIN (-6275 4350) $PN CM27
J 0
(-6265 4360);
DISPLAY 0.617021 (-6265 4360);
PAINT ORANGE (-6265 4360);
FORCEPROP 2 LASTPIN (-6275 4300) $PN D11
J 0
(-6265 4310);
DISPLAY 0.617021 (-6265 4310);
PAINT ORANGE (-6265 4310);
FORCEPROP 2 LASTPIN (-6275 4250) $PN D13
J 0
(-6265 4260);
DISPLAY 0.617021 (-6265 4260);
PAINT ORANGE (-6265 4260);
FORCEPROP 2 LASTPIN (-6275 4200) $PN D25
J 0
(-6265 4210);
DISPLAY 0.617021 (-6265 4210);
PAINT ORANGE (-6265 4210);
FORCEPROP 2 LASTPIN (-6275 4150) $PN D27
J 0
(-6265 4160);
DISPLAY 0.617021 (-6265 4160);
PAINT ORANGE (-6265 4160);
FORCEPROP 2 LASTPIN (-6275 4100) $PN D29
J 0
(-6265 4110);
DISPLAY 0.617021 (-6265 4110);
PAINT ORANGE (-6265 4110);
FORCEPROP 2 LASTPIN (-6275 4050) $PN D31
J 0
(-6265 4060);
DISPLAY 0.617021 (-6265 4060);
PAINT ORANGE (-6265 4060);
FORCEPROP 2 LASTPIN (-6275 4000) $PN D33
J 0
(-6265 4010);
DISPLAY 0.617021 (-6265 4010);
PAINT ORANGE (-6265 4010);
FORCEPROP 2 LASTPIN (-6275 3950) $PN D35
J 0
(-6265 3960);
DISPLAY 0.617021 (-6265 3960);
PAINT ORANGE (-6265 3960);
FORCEPROP 2 LASTPIN (-6275 3900) $PN D37
J 0
(-6265 3910);
DISPLAY 0.617021 (-6265 3910);
PAINT ORANGE (-6265 3910);
FORCEPROP 2 LASTPIN (-6275 3850) $PN D39
J 0
(-6265 3860);
DISPLAY 0.617021 (-6265 3860);
PAINT ORANGE (-6265 3860);
FORCEPROP 2 LASTPIN (-6275 3800) $PN D41
J 0
(-6265 3810);
DISPLAY 0.617021 (-6265 3810);
PAINT ORANGE (-6265 3810);
FORCEPROP 2 LASTPIN (-6275 3700) $PN D77
J 0
(-6265 3710);
DISPLAY 0.617021 (-6265 3710);
PAINT ORANGE (-6265 3710);
FORCEPROP 2 LASTPIN (-6275 3650) $PN E6
J 0
(-6265 3660);
DISPLAY 0.617021 (-6265 3660);
PAINT ORANGE (-6265 3660);
FORCEPROP 2 LASTPIN (-6275 3600) $PN E8
J 0
(-6265 3610);
DISPLAY 0.617021 (-6265 3610);
PAINT ORANGE (-6265 3610);
FORCEPROP 2 LASTPIN (-6275 3550) $PN E16
J 0
(-6265 3560);
DISPLAY 0.617021 (-6265 3560);
PAINT ORANGE (-6265 3560);
FORCEPROP 2 LASTPIN (-6275 3500) $PN E18
J 0
(-6265 3510);
DISPLAY 0.617021 (-6265 3510);
PAINT ORANGE (-6265 3510);
FORCEPROP 2 LASTPIN (-6275 3450) $PN E20
J 0
(-6265 3460);
DISPLAY 0.617021 (-6265 3460);
PAINT ORANGE (-6265 3460);
FORCEPROP 2 LASTPIN (-6275 3400) $PN E22
J 0
(-6265 3410);
DISPLAY 0.617021 (-6265 3410);
PAINT ORANGE (-6265 3410);
FORCEPROP 2 LASTPIN (-6275 3350) $PN E72
J 0
(-6265 3360);
DISPLAY 0.617021 (-6265 3360);
PAINT ORANGE (-6265 3360);
FORCEPROP 2 LASTPIN (-6275 3300) $PN E74
J 0
(-6265 3310);
DISPLAY 0.617021 (-6265 3310);
PAINT ORANGE (-6265 3310);
FORCEPROP 2 LASTPIN (-6275 3250) $PN E76
J 0
(-6265 3260);
DISPLAY 0.617021 (-6265 3260);
PAINT ORANGE (-6265 3260);
FORCEPROP 2 LASTPIN (-6275 3200) $PN F5
J 0
(-6265 3210);
DISPLAY 0.617021 (-6265 3210);
PAINT ORANGE (-6265 3210);
FORCEPROP 2 LASTPIN (-6275 3150) $PN F17
J 0
(-6265 3160);
DISPLAY 0.617021 (-6265 3160);
PAINT ORANGE (-6265 3160);
FORCEPROP 2 LASTPIN (-6275 3100) $PN F19
J 0
(-6265 3110);
DISPLAY 0.617021 (-6265 3110);
PAINT ORANGE (-6265 3110);
FORCEPROP 2 LASTPIN (-6275 3050) $PN F25
J 0
(-6265 3060);
DISPLAY 0.617021 (-6265 3060);
PAINT ORANGE (-6265 3060);
FORCEPROP 2 LASTPIN (-6275 3000) $PN F31
J 0
(-6265 3010);
DISPLAY 0.617021 (-6265 3010);
PAINT ORANGE (-6265 3010);
FORCEPROP 2 LASTPIN (-6275 2950) $PN F37
J 0
(-6265 2960);
DISPLAY 0.617021 (-6265 2960);
PAINT ORANGE (-6265 2960);
FORCEPROP 2 LASTPIN (-6275 2900) $PN F43
J 0
(-6265 2910);
DISPLAY 0.617021 (-6265 2910);
PAINT ORANGE (-6265 2910);
FORCEPROP 2 LASTPIN (-6275 2850) $PN F67
J 0
(-6265 2860);
DISPLAY 0.617021 (-6265 2860);
PAINT ORANGE (-6265 2860);
FORCEPROP 2 LASTPIN (-6275 2800) $PN F69
J 0
(-6265 2810);
DISPLAY 0.617021 (-6265 2810);
PAINT ORANGE (-6265 2810);
FORCEPROP 2 LASTPIN (-6275 2750) $PN G4
J 0
(-6265 2760);
DISPLAY 0.617021 (-6265 2760);
PAINT ORANGE (-6265 2760);
FORCEPROP 2 LASTPIN (-6275 2700) $PN G8
J 0
(-6265 2710);
DISPLAY 0.617021 (-6265 2710);
PAINT ORANGE (-6265 2710);
FORCEPROP 2 LASTPIN (-6275 2650) $PN G22
J 0
(-6265 2660);
DISPLAY 0.617021 (-6265 2660);
PAINT ORANGE (-6265 2660);
FORCEPROP 2 LASTPIN (-6275 2600) $PN G24
J 0
(-6265 2610);
DISPLAY 0.617021 (-6265 2610);
PAINT ORANGE (-6265 2610);
FORCEPROP 2 LASTPIN (-6275 2550) $PN G26
J 0
(-6265 2560);
DISPLAY 0.617021 (-6265 2560);
PAINT ORANGE (-6265 2560);
FORCEPROP 2 LASTPIN (-6275 2500) $PN G30
J 0
(-6265 2510);
DISPLAY 0.617021 (-6265 2510);
PAINT ORANGE (-6265 2510);
FORCEPROP 2 LASTPIN (-6275 2450) $PN G32
J 0
(-6265 2460);
DISPLAY 0.617021 (-6265 2460);
PAINT ORANGE (-6265 2460);
FORCEPROP 2 LASTPIN (-6275 2400) $PN G36
J 0
(-6265 2410);
DISPLAY 0.617021 (-6265 2410);
PAINT ORANGE (-6265 2410);
FORCEPROP 2 LASTPIN (-6275 2350) $PN G38
J 0
(-6265 2360);
DISPLAY 0.617021 (-6265 2360);
PAINT ORANGE (-6265 2360);
FORCEPROP 2 LASTPIN (-6275 2300) $PN G42
J 0
(-6265 2310);
DISPLAY 0.617021 (-6265 2310);
PAINT ORANGE (-6265 2310);
FORCEPROP 2 LASTPIN (-6275 2250) $PN G66
J 0
(-6265 2260);
DISPLAY 0.617021 (-6265 2260);
PAINT ORANGE (-6265 2260);
FORCEPROP 2 LASTPIN (-6275 2200) $PN G70
J 0
(-6265 2210);
DISPLAY 0.617021 (-6265 2210);
PAINT ORANGE (-6265 2210);
FORCEPROP 2 LASTPIN (-6275 2150) $PN G76
J 0
(-6265 2160);
DISPLAY 0.617021 (-6265 2160);
PAINT ORANGE (-6265 2160);
FORCEPROP 2 LASTPIN (-6275 2100) $PN G78
J 0
(-6265 2110);
DISPLAY 0.617021 (-6265 2110);
PAINT ORANGE (-6265 2110);
FORCEPROP 2 LASTPIN (-6275 2050) $PN G80
J 0
(-6265 2060);
DISPLAY 0.617021 (-6265 2060);
PAINT ORANGE (-6265 2060);
FORCEPROP 2 LASTPIN (-6275 2000) $PN G82
J 0
(-6265 2010);
DISPLAY 0.617021 (-6265 2010);
PAINT ORANGE (-6265 2010);
FORCEPROP 2 LASTPIN (-6275 1950) $PN H3
J 0
(-6265 1960);
DISPLAY 0.617021 (-6265 1960);
PAINT ORANGE (-6265 1960);
FORCEPROP 2 LASTPIN (-6275 1900) $PN H11
J 0
(-6265 1910);
DISPLAY 0.617021 (-6265 1910);
PAINT ORANGE (-6265 1910);
FORCEPROP 2 LASTPIN (-6275 1850) $PN H25
J 0
(-6265 1860);
DISPLAY 0.617021 (-6265 1860);
PAINT ORANGE (-6265 1860);
FORCEPROP 2 LASTPIN (-6275 1800) $PN H27
J 0
(-6265 1810);
DISPLAY 0.617021 (-6265 1810);
PAINT ORANGE (-6265 1810);
FORCEPROP 2 LASTPIN (-6275 1750) $PN H29
J 0
(-6265 1760);
DISPLAY 0.617021 (-6265 1760);
PAINT ORANGE (-6265 1760);
FORCEPROP 2 LASTPIN (-6275 1700) $PN H31
J 0
(-6265 1710);
DISPLAY 0.617021 (-6265 1710);
PAINT ORANGE (-6265 1710);
FORCEPROP 2 LASTPIN (-6275 1650) $PN H33
J 0
(-6265 1660);
DISPLAY 0.617021 (-6265 1660);
PAINT ORANGE (-6265 1660);
FORCEPROP 2 LASTPIN (-6275 1600) $PN H35
J 0
(-6265 1610);
DISPLAY 0.617021 (-6265 1610);
PAINT ORANGE (-6265 1610);
FORCEPROP 2 LASTPIN (-6275 1550) $PN H37
J 0
(-6265 1560);
DISPLAY 0.617021 (-6265 1560);
PAINT ORANGE (-6265 1560);
FORCEPROP 2 LASTPIN (-6275 1500) $PN H39
J 0
(-6265 1510);
DISPLAY 0.617021 (-6265 1510);
PAINT ORANGE (-6265 1510);
FORCEPROP 2 LASTPIN (-6275 1450) $PN H41
J 0
(-6265 1460);
DISPLAY 0.617021 (-6265 1460);
PAINT ORANGE (-6265 1460);
FORCEPROP 2 LASTPIN (-6275 1400) $PN H65
J 0
(-6265 1410);
DISPLAY 0.617021 (-6265 1410);
PAINT ORANGE (-6265 1410);
FORCEPROP 2 LASTPIN (-6275 1350) $PN H71
J 0
(-6265 1360);
DISPLAY 0.617021 (-6265 1360);
PAINT ORANGE (-6265 1360);
FORCEPROP 2 LASTPIN (-6275 1300) $PN H75
J 0
(-6265 1310);
DISPLAY 0.617021 (-6265 1310);
PAINT ORANGE (-6265 1310);
FORCEPROP 2 LASTPIN (-6275 1250) $PN DN44
J 0
(-6265 1260);
DISPLAY 0.617021 (-6265 1260);
PAINT ORANGE (-6265 1260);
FORCEPROP 2 LASTPIN (-6275 1200) $PN J4
J 0
(-6265 1210);
DISPLAY 0.617021 (-6265 1210);
PAINT ORANGE (-6265 1210);
FORCEPROP 2 LASTPIN (-6275 1150) $PN J12
J 0
(-6265 1160);
DISPLAY 0.617021 (-6265 1160);
PAINT ORANGE (-6265 1160);
FORCEPROP 2 LASTPIN (-6275 1100) $PN J14
J 0
(-6265 1110);
DISPLAY 0.617021 (-6265 1110);
PAINT ORANGE (-6265 1110);
FORCEPROP 2 LASTPIN (-6275 1050) $PN J22
J 0
(-6265 1060);
DISPLAY 0.617021 (-6265 1060);
PAINT ORANGE (-6265 1060);
FORCEPROP 2 LASTPIN (-6275 1000) $PN J26
J 0
(-6265 1010);
DISPLAY 0.617021 (-6265 1010);
PAINT ORANGE (-6265 1010);
FORCEPROP 2 LASTPIN (-6275 950) $PN J28
J 0
(-6265 960);
DISPLAY 0.617021 (-6265 960);
PAINT ORANGE (-6265 960);
FORCEPROP 2 LASTPIN (-6275 900) $PN J32
J 0
(-6265 910);
DISPLAY 0.617021 (-6265 910);
PAINT ORANGE (-6265 910);
FORCEPROP 2 LASTPIN (-6275 850) $PN J34
J 0
(-6265 860);
DISPLAY 0.617021 (-6265 860);
PAINT ORANGE (-6265 860);
FORCEPROP 2 LASTPIN (-6275 800) $PN J38
J 0
(-6265 810);
DISPLAY 0.617021 (-6265 810);
PAINT ORANGE (-6265 810);
FORCEPROP 2 LASTPIN (-6275 750) $PN J40
J 0
(-6265 760);
DISPLAY 0.617021 (-6265 760);
PAINT ORANGE (-6265 760);
FORCEPROP 2 LASTPIN (-6275 700) $PN J72
J 0
(-6265 710);
DISPLAY 0.617021 (-6265 710);
PAINT ORANGE (-6265 710);
FORCEPROP 2 LASTPIN (-6275 650) $PN J74
J 0
(-6265 660);
DISPLAY 0.617021 (-6265 660);
PAINT ORANGE (-6265 660);
FORCEPROP 2 LASTPIN (-7475 4600) $PN B9
J 2
(-7485 4610);
DISPLAY 0.617021 (-7485 4610);
PAINT ORANGE (-7485 4610);
FORCEPROP 2 LASTPIN (-7475 4300) $PN C80
J 2
(-7485 4310);
DISPLAY 0.617021 (-7485 4310);
PAINT ORANGE (-7485 4310);
FORCEPROP 2 LASTPIN (-6275 3750) $PN D43
J 0
(-6265 3760);
DISPLAY 0.617021 (-6265 3760);
PAINT ORANGE (-6265 3760);
FORCEPROP 1 LAST PACK_TYPE BGA1
J 0
(-7425 4900);
PAINT SKYBLUE (-7425 4900);
DISPLAY INVISIBLE (-7425 4900);
FORCEPROP 2 LAST SEC_TYPE BGA1
J 0
(-7425 4900);
DISPLAY 1.021277 (-7425 4900);
PAINT ORANGE (-7425 4900);
DISPLAY INVISIBLE (-7425 4900);
FORCEPROP 2 LAST CDS_LIB chpset_lib
J 0
(-6875 2600);
PAINT ORANGE (-6875 2600);
DISPLAY INVISIBLE (-6875 2600);
FORCEPROP 2 LAST SEC 23
J 0
(-7425 4900);
DISPLAY 0.680851 (-7425 4900);
PAINT MONO (-7425 4900);
DISPLAY INVISIBLE (-7425 4900);
FORCEPROP 2 LAST CDS_LOCATION U2D1
J 0
(-7425 4850);
DISPLAY 0.617021 (-7425 4850);
PAINT AQUA (-7425 4850);
DISPLAY INVISIBLE (-7425 4850);
FORCEPROP 1 LAST PATH I20
J 0
(-6875 4800);
PAINT GREEN (-6875 4800);
DISPLAY INVISIBLE (-6875 4800);
FORCEADD SKX_EXT_B..24
(-5025 2625);
FORCEPROP 1 LAST LOCATION U2D1
J 0
(-5575 4875);
DISPLAY 0.617021 (-5575 4875);
PAINT AQUA (-5575 4875);
FORCEPROP 1 LAST PART_NUMBER TBD
J 0
(-5575 475);
DISPLAY 0.617021 (-5575 475);
PAINT BLUE (-5575 475);
FORCEPROP 1 LAST MATERIAL IC
J 0
(-5575 4825);
DISPLAY 0.617021 (-5575 4825);
PAINT SKYBLUE (-5575 4825);
FORCEPROP 2 LASTPIN (-5625 4625) $PN J76
J 2
(-5635 4635);
DISPLAY 0.617021 (-5635 4635);
PAINT ORANGE (-5635 4635);
FORCEPROP 2 LASTPIN (-5625 4575) $PN J82
J 2
(-5635 4585);
DISPLAY 0.617021 (-5635 4585);
PAINT ORANGE (-5635 4585);
FORCEPROP 2 LASTPIN (-5625 4525) $PN J84
J 2
(-5635 4535);
DISPLAY 0.617021 (-5635 4535);
PAINT ORANGE (-5635 4535);
FORCEPROP 2 LASTPIN (-5625 4475) $PN K1
J 2
(-5635 4485);
DISPLAY 0.617021 (-5635 4485);
PAINT ORANGE (-5635 4485);
FORCEPROP 2 LASTPIN (-5625 4375) $PN K13
J 2
(-5635 4385);
DISPLAY 0.617021 (-5635 4385);
PAINT ORANGE (-5635 4385);
FORCEPROP 2 LASTPIN (-5625 4325) $PN K17
J 2
(-5635 4335);
DISPLAY 0.617021 (-5635 4335);
PAINT ORANGE (-5635 4335);
FORCEPROP 2 LASTPIN (-5625 4275) $PN DB7
J 2
(-5635 4285);
DISPLAY 0.617021 (-5635 4285);
PAINT ORANGE (-5635 4285);
FORCEPROP 2 LASTPIN (-5625 4225) $PN K27
J 2
(-5635 4235);
DISPLAY 0.617021 (-5635 4235);
PAINT ORANGE (-5635 4235);
FORCEPROP 2 LASTPIN (-5625 4175) $PN K33
J 2
(-5635 4185);
DISPLAY 0.617021 (-5635 4185);
PAINT ORANGE (-5635 4185);
FORCEPROP 2 LASTPIN (-5625 4125) $PN K39
J 2
(-5635 4135);
DISPLAY 0.617021 (-5635 4135);
PAINT ORANGE (-5635 4135);
FORCEPROP 2 LASTPIN (-5625 4075) $PN K65
J 2
(-5635 4085);
DISPLAY 0.617021 (-5635 4085);
PAINT ORANGE (-5635 4085);
FORCEPROP 2 LASTPIN (-5625 4025) $PN K67
J 2
(-5635 4035);
DISPLAY 0.617021 (-5635 4035);
PAINT ORANGE (-5635 4035);
FORCEPROP 2 LASTPIN (-5625 3925) $PN K71
J 2
(-5635 3935);
DISPLAY 0.617021 (-5635 3935);
PAINT ORANGE (-5635 3935);
FORCEPROP 2 LASTPIN (-5625 3875) $PN K73
J 2
(-5635 3885);
DISPLAY 0.617021 (-5635 3885);
PAINT ORANGE (-5635 3885);
FORCEPROP 2 LASTPIN (-5625 3825) $PN K77
J 2
(-5635 3835);
DISPLAY 0.617021 (-5635 3835);
PAINT ORANGE (-5635 3835);
FORCEPROP 2 LASTPIN (-5625 3775) $PN K81
J 2
(-5635 3785);
DISPLAY 0.617021 (-5635 3785);
PAINT ORANGE (-5635 3785);
FORCEPROP 2 LASTPIN (-5625 3725) $PN K83
J 2
(-5635 3735);
DISPLAY 0.617021 (-5635 3735);
PAINT ORANGE (-5635 3735);
FORCEPROP 2 LASTPIN (-5625 3675) $PN K85
J 2
(-5635 3685);
DISPLAY 0.617021 (-5635 3685);
PAINT ORANGE (-5635 3685);
FORCEPROP 2 LASTPIN (-5625 3625) $PN L10
J 2
(-5635 3635);
DISPLAY 0.617021 (-5635 3635);
PAINT ORANGE (-5635 3635);
FORCEPROP 2 LASTPIN (-5625 3575) $PN L2
J 2
(-5635 3585);
DISPLAY 0.617021 (-5635 3585);
PAINT ORANGE (-5635 3585);
FORCEPROP 2 LASTPIN (-5625 3525) $PN L6
J 2
(-5635 3535);
DISPLAY 0.617021 (-5635 3535);
PAINT ORANGE (-5635 3535);
FORCEPROP 2 LASTPIN (-5625 3475) $PN L20
J 2
(-5635 3485);
DISPLAY 0.617021 (-5635 3485);
PAINT ORANGE (-5635 3485);
FORCEPROP 2 LASTPIN (-5625 3425) $PN L22
J 2
(-5635 3435);
DISPLAY 0.617021 (-5635 3435);
PAINT ORANGE (-5635 3435);
FORCEPROP 2 LASTPIN (-5625 3375) $PN L72
J 2
(-5635 3385);
DISPLAY 0.617021 (-5635 3385);
PAINT ORANGE (-5635 3385);
FORCEPROP 2 LASTPIN (-5625 3325) $PN L78
J 2
(-5635 3335);
DISPLAY 0.617021 (-5635 3335);
PAINT ORANGE (-5635 3335);
FORCEPROP 2 LASTPIN (-5625 3275) $PN L80
J 2
(-5635 3285);
DISPLAY 0.617021 (-5635 3285);
PAINT ORANGE (-5635 3285);
FORCEPROP 2 LASTPIN (-5625 3225) $PN L82
J 2
(-5635 3235);
DISPLAY 0.617021 (-5635 3235);
PAINT ORANGE (-5635 3235);
FORCEPROP 2 LASTPIN (-5625 3175) $PN BT9
J 2
(-5635 3185);
DISPLAY 0.617021 (-5635 3185);
PAINT ORANGE (-5635 3185);
FORCEPROP 2 LASTPIN (-5625 3125) $PN CT7
J 2
(-5635 3135);
DISPLAY 0.617021 (-5635 3135);
PAINT ORANGE (-5635 3135);
FORCEPROP 2 LASTPIN (-5625 3075) $PN M15
J 2
(-5635 3085);
DISPLAY 0.617021 (-5635 3085);
PAINT ORANGE (-5635 3085);
FORCEPROP 2 LASTPIN (-5625 3025) $PN M17
J 2
(-5635 3035);
DISPLAY 0.617021 (-5635 3035);
PAINT ORANGE (-5635 3035);
FORCEPROP 2 LASTPIN (-5625 2975) $PN M19
J 2
(-5635 2985);
DISPLAY 0.617021 (-5635 2985);
PAINT ORANGE (-5635 2985);
FORCEPROP 2 LASTPIN (-5625 2925) $PN M23
J 2
(-5635 2935);
DISPLAY 0.617021 (-5635 2935);
PAINT ORANGE (-5635 2935);
FORCEPROP 2 LASTPIN (-5625 2875) $PN M25
J 2
(-5635 2885);
DISPLAY 0.617021 (-5635 2885);
PAINT ORANGE (-5635 2885);
FORCEPROP 2 LASTPIN (-5625 2825) $PN M27
J 2
(-5635 2835);
DISPLAY 0.617021 (-5635 2835);
PAINT ORANGE (-5635 2835);
FORCEPROP 2 LASTPIN (-5625 2775) $PN M29
J 2
(-5635 2785);
DISPLAY 0.617021 (-5635 2785);
PAINT ORANGE (-5635 2785);
FORCEPROP 2 LASTPIN (-5625 2725) $PN M31
J 2
(-5635 2735);
DISPLAY 0.617021 (-5635 2735);
PAINT ORANGE (-5635 2735);
FORCEPROP 2 LASTPIN (-5625 2675) $PN M33
J 2
(-5635 2685);
DISPLAY 0.617021 (-5635 2685);
PAINT ORANGE (-5635 2685);
FORCEPROP 2 LASTPIN (-5625 2625) $PN M35
J 2
(-5635 2635);
DISPLAY 0.617021 (-5635 2635);
PAINT ORANGE (-5635 2635);
FORCEPROP 2 LASTPIN (-5625 2575) $PN M37
J 2
(-5635 2585);
DISPLAY 0.617021 (-5635 2585);
PAINT ORANGE (-5635 2585);
FORCEPROP 2 LASTPIN (-5625 2525) $PN M39
J 2
(-5635 2535);
DISPLAY 0.617021 (-5635 2535);
PAINT ORANGE (-5635 2535);
FORCEPROP 2 LASTPIN (-5625 2475) $PN M41
J 2
(-5635 2485);
DISPLAY 0.617021 (-5635 2485);
PAINT ORANGE (-5635 2485);
FORCEPROP 2 LASTPIN (-5625 2425) $PN M43
J 2
(-5635 2435);
DISPLAY 0.617021 (-5635 2435);
PAINT ORANGE (-5635 2435);
FORCEPROP 2 LASTPIN (-5625 2375) $PN M65
J 2
(-5635 2385);
DISPLAY 0.617021 (-5635 2385);
PAINT ORANGE (-5635 2385);
FORCEPROP 2 LASTPIN (-5625 2325) $PN M71
J 2
(-5635 2335);
DISPLAY 0.617021 (-5635 2335);
PAINT ORANGE (-5635 2335);
FORCEPROP 2 LASTPIN (-5625 2275) $PN M79
J 2
(-5635 2285);
DISPLAY 0.617021 (-5635 2285);
PAINT ORANGE (-5635 2285);
FORCEPROP 2 LASTPIN (-5625 2225) $PN M83
J 2
(-5635 2235);
DISPLAY 0.617021 (-5635 2235);
PAINT ORANGE (-5635 2235);
FORCEPROP 2 LASTPIN (-5625 2175) $PN M85
J 2
(-5635 2185);
DISPLAY 0.617021 (-5635 2185);
PAINT ORANGE (-5635 2185);
FORCEPROP 2 LASTPIN (-5625 2125) $PN DM19
J 2
(-5635 2135);
DISPLAY 0.617021 (-5635 2135);
PAINT ORANGE (-5635 2135);
FORCEPROP 2 LASTPIN (-5625 2075) $PN N20
J 2
(-5635 2085);
DISPLAY 0.617021 (-5635 2085);
PAINT ORANGE (-5635 2085);
FORCEPROP 2 LASTPIN (-5625 2025) $PN N22
J 2
(-5635 2035);
DISPLAY 0.617021 (-5635 2035);
PAINT ORANGE (-5635 2035);
FORCEPROP 2 LASTPIN (-5625 1975) $PN N6
J 2
(-5635 1985);
DISPLAY 0.617021 (-5635 1985);
PAINT ORANGE (-5635 1985);
FORCEPROP 2 LASTPIN (-5625 1925) $PN N66
J 2
(-5635 1935);
DISPLAY 0.617021 (-5635 1935);
PAINT ORANGE (-5635 1935);
FORCEPROP 2 LASTPIN (-5625 1875) $PN N70
J 2
(-5635 1885);
DISPLAY 0.617021 (-5635 1885);
PAINT ORANGE (-5635 1885);
FORCEPROP 2 LASTPIN (-5625 1825) $PN N72
J 2
(-5635 1835);
DISPLAY 0.617021 (-5635 1835);
PAINT ORANGE (-5635 1835);
FORCEPROP 2 LASTPIN (-5625 1775) $PN N74
J 2
(-5635 1785);
DISPLAY 0.617021 (-5635 1785);
PAINT ORANGE (-5635 1785);
FORCEPROP 2 LASTPIN (-5625 1725) $PN N76
J 2
(-5635 1735);
DISPLAY 0.617021 (-5635 1735);
PAINT ORANGE (-5635 1735);
FORCEPROP 2 LASTPIN (-5625 1675) $PN N78
J 2
(-5635 1685);
DISPLAY 0.617021 (-5635 1685);
PAINT ORANGE (-5635 1685);
FORCEPROP 2 LASTPIN (-5625 1625) $PN N4
J 2
(-5635 1635);
DISPLAY 0.617021 (-5635 1635);
PAINT ORANGE (-5635 1635);
FORCEPROP 2 LASTPIN (-5625 1575) $PN N8
J 2
(-5635 1585);
DISPLAY 0.617021 (-5635 1585);
PAINT ORANGE (-5635 1585);
FORCEPROP 2 LASTPIN (-5625 1525) $PN P11
J 2
(-5635 1535);
DISPLAY 0.617021 (-5635 1535);
PAINT ORANGE (-5635 1535);
FORCEPROP 2 LASTPIN (-5625 1475) $PN P15
J 2
(-5635 1485);
DISPLAY 0.617021 (-5635 1485);
PAINT ORANGE (-5635 1485);
FORCEPROP 2 LASTPIN (-5625 1425) $PN P27
J 2
(-5635 1435);
DISPLAY 0.617021 (-5635 1435);
PAINT ORANGE (-5635 1435);
FORCEPROP 2 LASTPIN (-5625 1375) $PN P33
J 2
(-5635 1385);
DISPLAY 0.617021 (-5635 1385);
PAINT ORANGE (-5635 1385);
FORCEPROP 2 LASTPIN (-5625 1325) $PN P39
J 2
(-5635 1335);
DISPLAY 0.617021 (-5635 1335);
PAINT ORANGE (-5635 1335);
FORCEPROP 2 LASTPIN (-5625 1275) $PN P67
J 2
(-5635 1285);
DISPLAY 0.617021 (-5635 1285);
PAINT ORANGE (-5635 1285);
FORCEPROP 2 LASTPIN (-5625 1225) $PN P69
J 2
(-5635 1235);
DISPLAY 0.617021 (-5635 1235);
PAINT ORANGE (-5635 1235);
FORCEPROP 2 LASTPIN (-5625 1175) $PN P71
J 2
(-5635 1185);
DISPLAY 0.617021 (-5635 1185);
PAINT ORANGE (-5635 1185);
FORCEPROP 2 LASTPIN (-5625 1125) $PN P81
J 2
(-5635 1135);
DISPLAY 0.617021 (-5635 1135);
PAINT ORANGE (-5635 1135);
FORCEPROP 2 LASTPIN (-5625 1075) $PN P83
J 2
(-5635 1085);
DISPLAY 0.617021 (-5635 1085);
PAINT ORANGE (-5635 1085);
FORCEPROP 2 LASTPIN (-5625 1025) $PN R14
J 2
(-5635 1035);
DISPLAY 0.617021 (-5635 1035);
PAINT ORANGE (-5635 1035);
FORCEPROP 2 LASTPIN (-5625 975) $PN R18
J 2
(-5635 985);
DISPLAY 0.617021 (-5635 985);
PAINT ORANGE (-5635 985);
FORCEPROP 2 LASTPIN (-5625 925) $PN R2
J 2
(-5635 935);
DISPLAY 0.617021 (-5635 935);
PAINT ORANGE (-5635 935);
FORCEPROP 2 LASTPIN (-5625 875) $PN R4
J 2
(-5635 885);
DISPLAY 0.617021 (-5635 885);
PAINT ORANGE (-5635 885);
FORCEPROP 2 LASTPIN (-5625 825) $PN R22
J 2
(-5635 835);
DISPLAY 0.617021 (-5635 835);
PAINT ORANGE (-5635 835);
FORCEPROP 2 LASTPIN (-5625 775) $PN R26
J 2
(-5635 785);
DISPLAY 0.617021 (-5635 785);
PAINT ORANGE (-5635 785);
FORCEPROP 2 LASTPIN (-5625 725) $PN R28
J 2
(-5635 735);
DISPLAY 0.617021 (-5635 735);
PAINT ORANGE (-5635 735);
FORCEPROP 2 LASTPIN (-5625 675) $PN R32
J 2
(-5635 685);
DISPLAY 0.617021 (-5635 685);
PAINT ORANGE (-5635 685);
FORCEPROP 2 LASTPIN (-4425 4625) $PN R34
J 0
(-4415 4635);
DISPLAY 0.617021 (-4415 4635);
PAINT ORANGE (-4415 4635);
FORCEPROP 2 LASTPIN (-4425 4575) $PN R38
J 0
(-4415 4585);
DISPLAY 0.617021 (-4415 4585);
PAINT ORANGE (-4415 4585);
FORCEPROP 2 LASTPIN (-4425 4525) $PN R40
J 0
(-4415 4535);
DISPLAY 0.617021 (-4415 4535);
PAINT ORANGE (-4415 4535);
FORCEPROP 2 LASTPIN (-4425 4475) $PN R68
J 0
(-4415 4485);
DISPLAY 0.617021 (-4415 4485);
PAINT ORANGE (-4415 4485);
FORCEPROP 2 LASTPIN (-4425 4425) $PN R72
J 0
(-4415 4435);
DISPLAY 0.617021 (-4415 4435);
PAINT ORANGE (-4415 4435);
FORCEPROP 2 LASTPIN (-4425 4375) $PN R78
J 0
(-4415 4385);
DISPLAY 0.617021 (-4415 4385);
PAINT ORANGE (-4415 4385);
FORCEPROP 2 LASTPIN (-4425 4325) $PN R86
J 0
(-4415 4335);
DISPLAY 0.617021 (-4415 4335);
PAINT ORANGE (-4415 4335);
FORCEPROP 2 LASTPIN (-4425 4275) $PN T13
J 0
(-4415 4285);
DISPLAY 0.617021 (-4415 4285);
PAINT ORANGE (-4415 4285);
FORCEPROP 2 LASTPIN (-4425 4225) $PN T17
J 0
(-4415 4235);
DISPLAY 0.617021 (-4415 4235);
PAINT ORANGE (-4415 4235);
FORCEPROP 2 LASTPIN (-4425 4175) $PN T25
J 0
(-4415 4185);
DISPLAY 0.617021 (-4415 4185);
PAINT ORANGE (-4415 4185);
FORCEPROP 2 LASTPIN (-4425 4125) $PN T29
J 0
(-4415 4135);
DISPLAY 0.617021 (-4415 4135);
PAINT ORANGE (-4415 4135);
FORCEPROP 2 LASTPIN (-4425 4075) $PN T31
J 0
(-4415 4085);
DISPLAY 0.617021 (-4415 4085);
PAINT ORANGE (-4415 4085);
FORCEPROP 2 LASTPIN (-4425 4025) $PN T35
J 0
(-4415 4035);
DISPLAY 0.617021 (-4415 4035);
PAINT ORANGE (-4415 4035);
FORCEPROP 2 LASTPIN (-4425 3975) $PN T37
J 0
(-4415 3985);
DISPLAY 0.617021 (-4415 3985);
PAINT ORANGE (-4415 3985);
FORCEPROP 2 LASTPIN (-4425 3925) $PN T41
J 0
(-4415 3935);
DISPLAY 0.617021 (-4415 3935);
PAINT ORANGE (-4415 3935);
FORCEPROP 2 LASTPIN (-4425 3875) $PN T65
J 0
(-4415 3885);
DISPLAY 0.617021 (-4415 3885);
PAINT ORANGE (-4415 3885);
FORCEPROP 2 LASTPIN (-4425 3825) $PN T73
J 0
(-4415 3835);
DISPLAY 0.617021 (-4415 3835);
PAINT ORANGE (-4415 3835);
FORCEPROP 2 LASTPIN (-4425 3775) $PN T77
J 0
(-4415 3785);
DISPLAY 0.617021 (-4415 3785);
PAINT ORANGE (-4415 3785);
FORCEPROP 2 LASTPIN (-4425 3725) $PN T83
J 0
(-4415 3735);
DISPLAY 0.617021 (-4415 3735);
PAINT ORANGE (-4415 3735);
FORCEPROP 2 LASTPIN (-4425 3675) $PN T85
J 0
(-4415 3685);
DISPLAY 0.617021 (-4415 3685);
PAINT ORANGE (-4415 3685);
FORCEPROP 2 LASTPIN (-4425 3575) $PN U4
J 0
(-4415 3585);
DISPLAY 0.617021 (-4415 3585);
PAINT ORANGE (-4415 3585);
FORCEPROP 2 LASTPIN (-4425 3525) $PN U6
J 0
(-4415 3535);
DISPLAY 0.617021 (-4415 3535);
PAINT ORANGE (-4415 3535);
FORCEPROP 2 LASTPIN (-4425 3475) $PN U20
J 0
(-4415 3485);
DISPLAY 0.617021 (-4415 3485);
PAINT ORANGE (-4415 3485);
FORCEPROP 2 LASTPIN (-4425 3425) $PN U22
J 0
(-4415 3435);
DISPLAY 0.617021 (-4415 3435);
PAINT ORANGE (-4415 3435);
FORCEPROP 2 LASTPIN (-4425 3375) $PN U24
J 0
(-4415 3385);
DISPLAY 0.617021 (-4415 3385);
PAINT ORANGE (-4415 3385);
FORCEPROP 2 LASTPIN (-4425 3325) $PN U30
J 0
(-4415 3335);
DISPLAY 0.617021 (-4415 3335);
PAINT ORANGE (-4415 3335);
FORCEPROP 2 LASTPIN (-4425 3275) $PN U36
J 0
(-4415 3285);
DISPLAY 0.617021 (-4415 3285);
PAINT ORANGE (-4415 3285);
FORCEPROP 2 LASTPIN (-4425 3225) $PN U42
J 0
(-4415 3235);
DISPLAY 0.617021 (-4415 3235);
PAINT ORANGE (-4415 3235);
FORCEPROP 2 LASTPIN (-4425 3175) $PN U68
J 0
(-4415 3185);
DISPLAY 0.617021 (-4415 3185);
PAINT ORANGE (-4415 3185);
FORCEPROP 2 LASTPIN (-4425 3125) $PN U70
J 0
(-4415 3135);
DISPLAY 0.617021 (-4415 3135);
PAINT ORANGE (-4415 3135);
FORCEPROP 2 LASTPIN (-4425 3075) $PN U74
J 0
(-4415 3085);
DISPLAY 0.617021 (-4415 3085);
PAINT ORANGE (-4415 3085);
FORCEPROP 2 LASTPIN (-4425 3025) $PN U76
J 0
(-4415 3035);
DISPLAY 0.617021 (-4415 3035);
PAINT ORANGE (-4415 3035);
FORCEPROP 2 LASTPIN (-4425 2975) $PN U78
J 0
(-4415 2985);
DISPLAY 0.617021 (-4415 2985);
PAINT ORANGE (-4415 2985);
FORCEPROP 2 LASTPIN (-4425 2925) $PN U80
J 0
(-4415 2935);
DISPLAY 0.617021 (-4415 2935);
PAINT ORANGE (-4415 2935);
FORCEPROP 2 LASTPIN (-4425 2875) $PN U86
J 0
(-4415 2885);
DISPLAY 0.617021 (-4415 2885);
PAINT ORANGE (-4415 2885);
FORCEPROP 2 LASTPIN (-4425 2825) $PN V1
J 0
(-4415 2835);
DISPLAY 0.617021 (-4415 2835);
PAINT ORANGE (-4415 2835);
FORCEPROP 2 LASTPIN (-4425 2775) $PN V5
J 0
(-4415 2785);
DISPLAY 0.617021 (-4415 2785);
PAINT ORANGE (-4415 2785);
FORCEPROP 2 LASTPIN (-4425 2725) $PN V9
J 0
(-4415 2735);
DISPLAY 0.617021 (-4415 2735);
PAINT ORANGE (-4415 2735);
FORCEPROP 2 LASTPIN (-4425 2675) $PN V13
J 0
(-4415 2685);
DISPLAY 0.617021 (-4415 2685);
PAINT ORANGE (-4415 2685);
FORCEPROP 2 LASTPIN (-4425 2625) $PN V15
J 0
(-4415 2635);
DISPLAY 0.617021 (-4415 2635);
PAINT ORANGE (-4415 2635);
FORCEPROP 2 LASTPIN (-4425 2575) $PN V21
J 0
(-4415 2585);
DISPLAY 0.617021 (-4415 2585);
PAINT ORANGE (-4415 2585);
FORCEPROP 2 LASTPIN (-4425 2525) $PN V23
J 0
(-4415 2535);
DISPLAY 0.617021 (-4415 2535);
PAINT ORANGE (-4415 2535);
FORCEPROP 2 LASTPIN (-4425 2475) $PN V43
J 0
(-4415 2485);
DISPLAY 0.617021 (-4415 2485);
PAINT ORANGE (-4415 2485);
FORCEPROP 2 LASTPIN (-4425 2425) $PN V73
J 0
(-4415 2435);
DISPLAY 0.617021 (-4415 2435);
PAINT ORANGE (-4415 2435);
FORCEPROP 2 LASTPIN (-4425 2375) $PN V75
J 0
(-4415 2385);
DISPLAY 0.617021 (-4415 2385);
PAINT ORANGE (-4415 2385);
FORCEPROP 2 LASTPIN (-4425 2325) $PN V77
J 0
(-4415 2335);
DISPLAY 0.617021 (-4415 2335);
PAINT ORANGE (-4415 2335);
FORCEPROP 2 LASTPIN (-4425 2275) $PN V83
J 0
(-4415 2285);
DISPLAY 0.617021 (-4415 2285);
PAINT ORANGE (-4415 2285);
FORCEPROP 2 LASTPIN (-4425 2225) $PN W8
J 0
(-4415 2235);
DISPLAY 0.617021 (-4415 2235);
PAINT ORANGE (-4415 2235);
FORCEPROP 2 LASTPIN (-4425 2175) $PN AC56
J 0
(-4415 2185);
DISPLAY 0.617021 (-4415 2185);
PAINT ORANGE (-4415 2185);
FORCEPROP 2 LASTPIN (-4425 2125) $PN W12
J 0
(-4415 2135);
DISPLAY 0.617021 (-4415 2135);
PAINT ORANGE (-4415 2135);
FORCEPROP 2 LASTPIN (-4425 2075) $PN W22
J 0
(-4415 2085);
DISPLAY 0.617021 (-4415 2085);
PAINT ORANGE (-4415 2085);
FORCEPROP 2 LASTPIN (-4425 2025) $PN W24
J 0
(-4415 2035);
DISPLAY 0.617021 (-4415 2035);
PAINT ORANGE (-4415 2035);
FORCEPROP 2 LASTPIN (-4425 1975) $PN W26
J 0
(-4415 1985);
DISPLAY 0.617021 (-4415 1985);
PAINT ORANGE (-4415 1985);
FORCEPROP 2 LASTPIN (-4425 1925) $PN W28
J 0
(-4415 1935);
DISPLAY 0.617021 (-4415 1935);
PAINT ORANGE (-4415 1935);
FORCEPROP 2 LASTPIN (-4425 1875) $PN W30
J 0
(-4415 1885);
DISPLAY 0.617021 (-4415 1885);
PAINT ORANGE (-4415 1885);
FORCEPROP 2 LASTPIN (-4425 1825) $PN W32
J 0
(-4415 1835);
DISPLAY 0.617021 (-4415 1835);
PAINT ORANGE (-4415 1835);
FORCEPROP 2 LASTPIN (-4425 1775) $PN W34
J 0
(-4415 1785);
DISPLAY 0.617021 (-4415 1785);
PAINT ORANGE (-4415 1785);
FORCEPROP 2 LASTPIN (-4425 1725) $PN W36
J 0
(-4415 1735);
DISPLAY 0.617021 (-4415 1735);
PAINT ORANGE (-4415 1735);
FORCEPROP 2 LASTPIN (-4425 1675) $PN W38
J 0
(-4415 1685);
DISPLAY 0.617021 (-4415 1685);
PAINT ORANGE (-4415 1685);
FORCEPROP 2 LASTPIN (-4425 1625) $PN W40
J 0
(-4415 1635);
DISPLAY 0.617021 (-4415 1635);
PAINT ORANGE (-4415 1635);
FORCEPROP 2 LASTPIN (-4425 1575) $PN W42
J 0
(-4415 1585);
DISPLAY 0.617021 (-4415 1585);
PAINT ORANGE (-4415 1585);
FORCEPROP 2 LASTPIN (-4425 1525) $PN W68
J 0
(-4415 1535);
DISPLAY 0.617021 (-4415 1535);
PAINT ORANGE (-4415 1535);
FORCEPROP 2 LASTPIN (-4425 1475) $PN W74
J 0
(-4415 1485);
DISPLAY 0.617021 (-4415 1485);
PAINT ORANGE (-4415 1485);
FORCEPROP 2 LASTPIN (-4425 1425) $PN W78
J 0
(-4415 1435);
DISPLAY 0.617021 (-4415 1435);
PAINT ORANGE (-4415 1435);
FORCEPROP 2 LASTPIN (-4425 1375) $PN W82
J 0
(-4415 1385);
DISPLAY 0.617021 (-4415 1385);
PAINT ORANGE (-4415 1385);
FORCEPROP 2 LASTPIN (-4425 1325) $PN Y15
J 0
(-4415 1335);
DISPLAY 0.617021 (-4415 1335);
PAINT ORANGE (-4415 1335);
FORCEPROP 2 LASTPIN (-4425 1275) $PN Y17
J 0
(-4415 1285);
DISPLAY 0.617021 (-4415 1285);
PAINT ORANGE (-4415 1285);
FORCEPROP 2 LASTPIN (-4425 1225) $PN Y5
J 0
(-4415 1235);
DISPLAY 0.617021 (-4415 1235);
PAINT ORANGE (-4415 1235);
FORCEPROP 2 LASTPIN (-4425 1175) $PN Y67
J 0
(-4415 1185);
DISPLAY 0.617021 (-4415 1185);
PAINT ORANGE (-4415 1185);
FORCEPROP 2 LASTPIN (-4425 1125) $PN Y7
J 0
(-4415 1135);
DISPLAY 0.617021 (-4415 1135);
PAINT ORANGE (-4415 1135);
FORCEPROP 2 LASTPIN (-4425 1075) $PN Y9
J 0
(-4415 1085);
DISPLAY 0.617021 (-4415 1085);
PAINT ORANGE (-4415 1085);
FORCEPROP 2 LASTPIN (-4425 1025) $PN Y71
J 0
(-4415 1035);
DISPLAY 0.617021 (-4415 1035);
PAINT ORANGE (-4415 1035);
FORCEPROP 2 LASTPIN (-4425 975) $PN Y73
J 0
(-4415 985);
DISPLAY 0.617021 (-4415 985);
PAINT ORANGE (-4415 985);
FORCEPROP 2 LASTPIN (-4425 925) $PN Y79
J 0
(-4415 935);
DISPLAY 0.617021 (-4415 935);
PAINT ORANGE (-4415 935);
FORCEPROP 2 LASTPIN (-4425 875) $PN Y81
J 0
(-4415 885);
DISPLAY 0.617021 (-4415 885);
PAINT ORANGE (-4415 885);
FORCEPROP 2 LASTPIN (-4425 825) $PN Y83
J 0
(-4415 835);
DISPLAY 0.617021 (-4415 835);
PAINT ORANGE (-4415 835);
FORCEPROP 2 LASTPIN (-4425 775) $PN Y85
J 0
(-4415 785);
DISPLAY 0.617021 (-4415 785);
PAINT ORANGE (-4415 785);
FORCEPROP 2 LASTPIN (-4425 725) $PN AA4
J 0
(-4415 735);
DISPLAY 0.617021 (-4415 735);
PAINT ORANGE (-4415 735);
FORCEPROP 2 LASTPIN (-4425 675) $PN AA16
J 0
(-4415 685);
DISPLAY 0.617021 (-4415 685);
PAINT ORANGE (-4415 685);
FORCEPROP 2 LASTPIN (-5625 4425) $PN K11
J 2
(-5635 4435);
DISPLAY 0.617021 (-5635 4435);
PAINT ORANGE (-5635 4435);
FORCEPROP 2 LASTPIN (-5625 3975) $PN K69
J 2
(-5635 3985);
DISPLAY 0.617021 (-5635 3985);
PAINT ORANGE (-5635 3985);
FORCEPROP 2 LASTPIN (-4425 3625) $PN U2
J 0
(-4415 3635);
DISPLAY 0.617021 (-4415 3635);
PAINT ORANGE (-4415 3635);
FORCEPROP 1 LAST PACK_TYPE BGA1
J 0
(-5575 4925);
PAINT SKYBLUE (-5575 4925);
DISPLAY INVISIBLE (-5575 4925);
FORCEPROP 2 LAST SEC_TYPE BGA1
J 0
(-5575 4925);
DISPLAY 1.021277 (-5575 4925);
PAINT ORANGE (-5575 4925);
DISPLAY INVISIBLE (-5575 4925);
FORCEPROP 2 LAST CDS_LIB chpset_lib
J 0
(-5025 2625);
PAINT ORANGE (-5025 2625);
DISPLAY INVISIBLE (-5025 2625);
FORCEPROP 2 LAST SEC 24
J 0
(-5575 4925);
DISPLAY 0.680851 (-5575 4925);
PAINT MONO (-5575 4925);
DISPLAY INVISIBLE (-5575 4925);
FORCEPROP 2 LAST CDS_LOCATION U2D1
J 0
(-5575 4875);
DISPLAY 0.617021 (-5575 4875);
PAINT AQUA (-5575 4875);
DISPLAY INVISIBLE (-5575 4875);
FORCEPROP 1 LAST PATH I21
J 0
(-5025 4825);
PAINT GREEN (-5025 4825);
DISPLAY INVISIBLE (-5025 4825);
FORCEADD SKX_EXT_B..25
(-3200 2625);
FORCEPROP 1 LAST LOCATION U2D1
J 0
(-3750 4875);
DISPLAY 0.617021 (-3750 4875);
PAINT AQUA (-3750 4875);
FORCEPROP 1 LAST PART_NUMBER TBD
J 0
(-3750 475);
DISPLAY 0.617021 (-3750 475);
PAINT BLUE (-3750 475);
FORCEPROP 1 LAST MATERIAL IC
J 0
(-3750 4825);
DISPLAY 0.617021 (-3750 4825);
PAINT SKYBLUE (-3750 4825);
FORCEPROP 2 LASTPIN (-3800 4625) $PN AA18
J 2
(-3810 4635);
DISPLAY 0.617021 (-3810 4635);
PAINT ORANGE (-3810 4635);
FORCEPROP 2 LASTPIN (-3800 4575) $PN AA22
J 2
(-3810 4585);
DISPLAY 0.617021 (-3810 4585);
PAINT ORANGE (-3810 4585);
FORCEPROP 2 LASTPIN (-3800 4525) $PN AA24
J 2
(-3810 4535);
DISPLAY 0.617021 (-3810 4535);
PAINT ORANGE (-3810 4535);
FORCEPROP 2 LASTPIN (-3800 4475) $PN AA30
J 2
(-3810 4485);
DISPLAY 0.617021 (-3810 4485);
PAINT ORANGE (-3810 4485);
FORCEPROP 2 LASTPIN (-3800 4425) $PN AA36
J 2
(-3810 4435);
DISPLAY 0.617021 (-3810 4435);
PAINT ORANGE (-3810 4435);
FORCEPROP 2 LASTPIN (-3800 4375) $PN AA42
J 2
(-3810 4385);
DISPLAY 0.617021 (-3810 4385);
PAINT ORANGE (-3810 4385);
FORCEPROP 2 LASTPIN (-3800 4325) $PN AA64
J 2
(-3810 4335);
DISPLAY 0.617021 (-3810 4335);
PAINT ORANGE (-3810 4335);
FORCEPROP 2 LASTPIN (-3800 4275) $PN AA66
J 2
(-3810 4285);
DISPLAY 0.617021 (-3810 4285);
PAINT ORANGE (-3810 4285);
FORCEPROP 2 LASTPIN (-3800 4225) $PN AA68
J 2
(-3810 4235);
DISPLAY 0.617021 (-3810 4235);
PAINT ORANGE (-3810 4235);
FORCEPROP 2 LASTPIN (-3800 4175) $PN AA76
J 2
(-3810 4185);
DISPLAY 0.617021 (-3810 4185);
PAINT ORANGE (-3810 4185);
FORCEPROP 2 LASTPIN (-3800 4125) $PN AA78
J 2
(-3810 4135);
DISPLAY 0.617021 (-3810 4135);
PAINT ORANGE (-3810 4135);
FORCEPROP 2 LASTPIN (-3800 4075) $PN AA80
J 2
(-3810 4085);
DISPLAY 0.617021 (-3810 4085);
PAINT ORANGE (-3810 4085);
FORCEPROP 2 LASTPIN (-3800 4025) $PN AA82
J 2
(-3810 4035);
DISPLAY 0.617021 (-3810 4035);
PAINT ORANGE (-3810 4035);
FORCEPROP 2 LASTPIN (-3800 3975) $PN AB1
J 2
(-3810 3985);
DISPLAY 0.617021 (-3810 3985);
PAINT ORANGE (-3810 3985);
FORCEPROP 2 LASTPIN (-3800 3925) $PN AB5
J 2
(-3810 3935);
DISPLAY 0.617021 (-3810 3935);
PAINT ORANGE (-3810 3935);
FORCEPROP 2 LASTPIN (-3800 3875) $PN AB11
J 2
(-3810 3885);
DISPLAY 0.617021 (-3810 3885);
PAINT ORANGE (-3810 3885);
FORCEPROP 2 LASTPIN (-3800 3825) $PN AB21
J 2
(-3810 3835);
DISPLAY 0.617021 (-3810 3835);
PAINT ORANGE (-3810 3835);
FORCEPROP 2 LASTPIN (-3800 3775) $PN AB23
J 2
(-3810 3785);
DISPLAY 0.617021 (-3810 3785);
PAINT ORANGE (-3810 3785);
FORCEPROP 2 LASTPIN (-3800 3725) $PN AB25
J 2
(-3810 3735);
DISPLAY 0.617021 (-3810 3735);
PAINT ORANGE (-3810 3735);
FORCEPROP 2 LASTPIN (-3800 3675) $PN AB29
J 2
(-3810 3685);
DISPLAY 0.617021 (-3810 3685);
PAINT ORANGE (-3810 3685);
FORCEPROP 2 LASTPIN (-3800 3625) $PN AB31
J 2
(-3810 3635);
DISPLAY 0.617021 (-3810 3635);
PAINT ORANGE (-3810 3635);
FORCEPROP 2 LASTPIN (-3800 3575) $PN AB35
J 2
(-3810 3585);
DISPLAY 0.617021 (-3810 3585);
PAINT ORANGE (-3810 3585);
FORCEPROP 2 LASTPIN (-3800 3525) $PN AB37
J 2
(-3810 3535);
DISPLAY 0.617021 (-3810 3535);
PAINT ORANGE (-3810 3535);
FORCEPROP 2 LASTPIN (-3800 3475) $PN AB41
J 2
(-3810 3485);
DISPLAY 0.617021 (-3810 3485);
PAINT ORANGE (-3810 3485);
FORCEPROP 2 LASTPIN (-3800 3425) $PN AB65
J 2
(-3810 3435);
DISPLAY 0.617021 (-3810 3435);
PAINT ORANGE (-3810 3435);
FORCEPROP 2 LASTPIN (-3800 3375) $PN AB69
J 2
(-3810 3385);
DISPLAY 0.617021 (-3810 3385);
PAINT ORANGE (-3810 3385);
FORCEPROP 2 LASTPIN (-3800 3325) $PN AB73
J 2
(-3810 3335);
DISPLAY 0.617021 (-3810 3335);
PAINT ORANGE (-3810 3335);
FORCEPROP 2 LASTPIN (-3800 3275) $PN AB79
J 2
(-3810 3285);
DISPLAY 0.617021 (-3810 3285);
PAINT ORANGE (-3810 3285);
FORCEPROP 2 LASTPIN (-3800 3225) $PN AB83
J 2
(-3810 3235);
DISPLAY 0.617021 (-3810 3235);
PAINT ORANGE (-3810 3235);
FORCEPROP 2 LASTPIN (-3800 3175) $PN AB85
J 2
(-3810 3185);
DISPLAY 0.617021 (-3810 3185);
PAINT ORANGE (-3810 3185);
FORCEPROP 2 LASTPIN (-3800 3125) $PN AC18
J 2
(-3810 3135);
DISPLAY 0.617021 (-3810 3135);
PAINT ORANGE (-3810 3135);
FORCEPROP 2 LASTPIN (-3800 3075) $PN AC22
J 2
(-3810 3085);
DISPLAY 0.617021 (-3810 3085);
PAINT ORANGE (-3810 3085);
FORCEPROP 2 LASTPIN (-3800 3025) $PN AC26
J 2
(-3810 3035);
DISPLAY 0.617021 (-3810 3035);
PAINT ORANGE (-3810 3035);
FORCEPROP 2 LASTPIN (-3800 2975) $PN AC28
J 2
(-3810 2985);
DISPLAY 0.617021 (-3810 2985);
PAINT ORANGE (-3810 2985);
FORCEPROP 2 LASTPIN (-3800 2925) $PN AC32
J 2
(-3810 2935);
DISPLAY 0.617021 (-3810 2935);
PAINT ORANGE (-3810 2935);
FORCEPROP 2 LASTPIN (-3800 2875) $PN AC34
J 2
(-3810 2885);
DISPLAY 0.617021 (-3810 2885);
PAINT ORANGE (-3810 2885);
FORCEPROP 2 LASTPIN (-3800 2825) $PN AC38
J 2
(-3810 2835);
DISPLAY 0.617021 (-3810 2835);
PAINT ORANGE (-3810 2835);
FORCEPROP 2 LASTPIN (-3800 2775) $PN AC40
J 2
(-3810 2785);
DISPLAY 0.617021 (-3810 2785);
PAINT ORANGE (-3810 2785);
FORCEPROP 2 LASTPIN (-3800 2725) $PN AC64
J 2
(-3810 2735);
DISPLAY 0.617021 (-3810 2735);
PAINT ORANGE (-3810 2735);
FORCEPROP 2 LASTPIN (-3800 2675) $PN AC70
J 2
(-3810 2685);
DISPLAY 0.617021 (-3810 2685);
PAINT ORANGE (-3810 2685);
FORCEPROP 2 LASTPIN (-3800 2625) $PN AC72
J 2
(-3810 2635);
DISPLAY 0.617021 (-3810 2635);
PAINT ORANGE (-3810 2635);
FORCEPROP 2 LASTPIN (-3800 2575) $PN AC78
J 2
(-3810 2585);
DISPLAY 0.617021 (-3810 2585);
PAINT ORANGE (-3810 2585);
FORCEPROP 2 LASTPIN (-3800 2525) $PN AC84
J 2
(-3810 2535);
DISPLAY 0.617021 (-3810 2535);
PAINT ORANGE (-3810 2535);
FORCEPROP 2 LASTPIN (-3800 2475) $PN AC86
J 2
(-3810 2485);
DISPLAY 0.617021 (-3810 2485);
PAINT ORANGE (-3810 2485);
FORCEPROP 2 LASTPIN (-3800 2425) $PN AD3
J 2
(-3810 2435);
DISPLAY 0.617021 (-3810 2435);
PAINT ORANGE (-3810 2435);
FORCEPROP 2 LASTPIN (-3800 2375) $PN AD7
J 2
(-3810 2385);
DISPLAY 0.617021 (-3810 2385);
PAINT ORANGE (-3810 2385);
FORCEPROP 2 LASTPIN (-3800 2325) $PN AD9
J 2
(-3810 2335);
DISPLAY 0.617021 (-3810 2335);
PAINT ORANGE (-3810 2335);
FORCEPROP 2 LASTPIN (-3800 2275) $PN AD11
J 2
(-3810 2285);
DISPLAY 0.617021 (-3810 2285);
PAINT ORANGE (-3810 2285);
FORCEPROP 2 LASTPIN (-3800 2225) $PN AD13
J 2
(-3810 2235);
DISPLAY 0.617021 (-3810 2235);
PAINT ORANGE (-3810 2235);
FORCEPROP 2 LASTPIN (-3800 2175) $PN AD15
J 2
(-3810 2185);
DISPLAY 0.617021 (-3810 2185);
PAINT ORANGE (-3810 2185);
FORCEPROP 2 LASTPIN (-3800 2125) $PN AD19
J 2
(-3810 2135);
DISPLAY 0.617021 (-3810 2135);
PAINT ORANGE (-3810 2135);
FORCEPROP 2 LASTPIN (-3800 2075) $PN AD21
J 2
(-3810 2085);
DISPLAY 0.617021 (-3810 2085);
PAINT ORANGE (-3810 2085);
FORCEPROP 2 LASTPIN (-3800 2025) $PN AD27
J 2
(-3810 2035);
DISPLAY 0.617021 (-3810 2035);
PAINT ORANGE (-3810 2035);
FORCEPROP 2 LASTPIN (-3800 1975) $PN AD33
J 2
(-3810 1985);
DISPLAY 0.617021 (-3810 1985);
PAINT ORANGE (-3810 1985);
FORCEPROP 2 LASTPIN (-3800 1925) $PN AD39
J 2
(-3810 1935);
DISPLAY 0.617021 (-3810 1935);
PAINT ORANGE (-3810 1935);
FORCEPROP 2 LASTPIN (-3800 1875) $PN AD43
J 2
(-3810 1885);
DISPLAY 0.617021 (-3810 1885);
PAINT ORANGE (-3810 1885);
FORCEPROP 2 LASTPIN (-3800 1825) $PN AD71
J 2
(-3810 1835);
DISPLAY 0.617021 (-3810 1835);
PAINT ORANGE (-3810 1835);
FORCEPROP 2 LASTPIN (-3800 1775) $PN AD73
J 2
(-3810 1785);
DISPLAY 0.617021 (-3810 1785);
PAINT ORANGE (-3810 1785);
FORCEPROP 2 LASTPIN (-3800 1725) $PN AD75
J 2
(-3810 1735);
DISPLAY 0.617021 (-3810 1735);
PAINT ORANGE (-3810 1735);
FORCEPROP 2 LASTPIN (-3800 1675) $PN AD81
J 2
(-3810 1685);
DISPLAY 0.617021 (-3810 1685);
PAINT ORANGE (-3810 1685);
FORCEPROP 2 LASTPIN (-3800 1625) $PN AD83
J 2
(-3810 1635);
DISPLAY 0.617021 (-3810 1635);
PAINT ORANGE (-3810 1635);
FORCEPROP 2 LASTPIN (-3800 1575) $PN AD85
J 2
(-3810 1585);
DISPLAY 0.617021 (-3810 1585);
PAINT ORANGE (-3810 1585);
FORCEPROP 2 LASTPIN (-3800 1525) $PN AE4
J 2
(-3810 1535);
DISPLAY 0.617021 (-3810 1535);
PAINT ORANGE (-3810 1535);
FORCEPROP 2 LASTPIN (-3800 1475) $PN AE8
J 2
(-3810 1485);
DISPLAY 0.617021 (-3810 1485);
PAINT ORANGE (-3810 1485);
FORCEPROP 2 LASTPIN (-3800 1425) $PN AC54
J 2
(-3810 1435);
DISPLAY 0.617021 (-3810 1435);
PAINT ORANGE (-3810 1435);
FORCEPROP 2 LASTPIN (-3800 1375) $PN AE16
J 2
(-3810 1385);
DISPLAY 0.617021 (-3810 1385);
PAINT ORANGE (-3810 1385);
FORCEPROP 2 LASTPIN (-3800 1325) $PN AE38
J 2
(-3810 1335);
DISPLAY 0.617021 (-3810 1335);
PAINT ORANGE (-3810 1335);
FORCEPROP 2 LASTPIN (-3800 1275) $PN AE40
J 2
(-3810 1285);
DISPLAY 0.617021 (-3810 1285);
PAINT ORANGE (-3810 1285);
FORCEPROP 2 LASTPIN (-3800 1225) $PN AE42
J 2
(-3810 1235);
DISPLAY 0.617021 (-3810 1235);
PAINT ORANGE (-3810 1235);
FORCEPROP 2 LASTPIN (-3800 1175) $PN AE64
J 2
(-3810 1185);
DISPLAY 0.617021 (-3810 1185);
PAINT ORANGE (-3810 1185);
FORCEPROP 2 LASTPIN (-3800 1125) $PN AE66
J 2
(-3810 1135);
DISPLAY 0.617021 (-3810 1135);
PAINT ORANGE (-3810 1135);
FORCEPROP 2 LASTPIN (-3800 1075) $PN AE68
J 2
(-3810 1085);
DISPLAY 0.617021 (-3810 1085);
PAINT ORANGE (-3810 1085);
FORCEPROP 2 LASTPIN (-3800 1025) $PN AE70
J 2
(-3810 1035);
DISPLAY 0.617021 (-3810 1035);
PAINT ORANGE (-3810 1035);
FORCEPROP 2 LASTPIN (-3800 975) $PN AE78
J 2
(-3810 985);
DISPLAY 0.617021 (-3810 985);
PAINT ORANGE (-3810 985);
FORCEPROP 2 LASTPIN (-3800 925) $PN AF1
J 2
(-3810 935);
DISPLAY 0.617021 (-3810 935);
PAINT ORANGE (-3810 935);
FORCEPROP 2 LASTPIN (-3800 875) $PN AC52
J 2
(-3810 885);
DISPLAY 0.617021 (-3810 885);
PAINT ORANGE (-3810 885);
FORCEPROP 2 LASTPIN (-3800 825) $PN AF9
J 2
(-3810 835);
DISPLAY 0.617021 (-3810 835);
PAINT ORANGE (-3810 835);
FORCEPROP 2 LASTPIN (-3800 775) $PN AF21
J 2
(-3810 785);
DISPLAY 0.617021 (-3810 785);
PAINT ORANGE (-3810 785);
FORCEPROP 2 LASTPIN (-3800 725) $PN AF23
J 2
(-3810 735);
DISPLAY 0.617021 (-3810 735);
PAINT ORANGE (-3810 735);
FORCEPROP 2 LASTPIN (-3800 675) $PN AF25
J 2
(-3810 685);
DISPLAY 0.617021 (-3810 685);
PAINT ORANGE (-3810 685);
FORCEPROP 2 LASTPIN (-2600 4625) $PN AF27
J 0
(-2590 4635);
DISPLAY 0.617021 (-2590 4635);
PAINT ORANGE (-2590 4635);
FORCEPROP 2 LASTPIN (-2600 4575) $PN AF29
J 0
(-2590 4585);
DISPLAY 0.617021 (-2590 4585);
PAINT ORANGE (-2590 4585);
FORCEPROP 2 LASTPIN (-2600 4475) $PN AF33
J 0
(-2590 4485);
DISPLAY 0.617021 (-2590 4485);
PAINT ORANGE (-2590 4485);
FORCEPROP 2 LASTPIN (-2600 4425) $PN AF37
J 0
(-2590 4435);
DISPLAY 0.617021 (-2590 4435);
PAINT ORANGE (-2590 4435);
FORCEPROP 2 LASTPIN (-2600 4375) $PN AF39
J 0
(-2590 4385);
DISPLAY 0.617021 (-2590 4385);
PAINT ORANGE (-2590 4385);
FORCEPROP 2 LASTPIN (-2600 4325) $PN AF41
J 0
(-2590 4335);
DISPLAY 0.617021 (-2590 4335);
PAINT ORANGE (-2590 4335);
FORCEPROP 2 LASTPIN (-2600 4275) $PN AF73
J 0
(-2590 4285);
DISPLAY 0.617021 (-2590 4285);
PAINT ORANGE (-2590 4285);
FORCEPROP 2 LASTPIN (-2600 4225) $PN AF77
J 0
(-2590 4235);
DISPLAY 0.617021 (-2590 4235);
PAINT ORANGE (-2590 4235);
FORCEPROP 2 LASTPIN (-2600 4175) $PN AF83
J 0
(-2590 4185);
DISPLAY 0.617021 (-2590 4185);
PAINT ORANGE (-2590 4185);
FORCEPROP 2 LASTPIN (-2600 4125) $PN AF85
J 0
(-2590 4135);
DISPLAY 0.617021 (-2590 4135);
PAINT ORANGE (-2590 4135);
FORCEPROP 2 LASTPIN (-2600 4075) $PN AG12
J 0
(-2590 4085);
DISPLAY 0.617021 (-2590 4085);
PAINT ORANGE (-2590 4085);
FORCEPROP 2 LASTPIN (-2600 4025) $PN AG14
J 0
(-2590 4035);
DISPLAY 0.617021 (-2590 4035);
PAINT ORANGE (-2590 4035);
FORCEPROP 2 LASTPIN (-2600 3975) $PN AG18
J 0
(-2590 3985);
DISPLAY 0.617021 (-2590 3985);
PAINT ORANGE (-2590 3985);
FORCEPROP 2 LASTPIN (-2600 3925) $PN AG36
J 0
(-2590 3935);
DISPLAY 0.617021 (-2590 3935);
PAINT ORANGE (-2590 3935);
FORCEPROP 2 LASTPIN (-2600 3875) $PN AG64
J 0
(-2590 3885);
DISPLAY 0.617021 (-2590 3885);
PAINT ORANGE (-2590 3885);
FORCEPROP 2 LASTPIN (-2600 3825) $PN AG70
J 0
(-2590 3835);
DISPLAY 0.617021 (-2590 3835);
PAINT ORANGE (-2590 3835);
FORCEPROP 2 LASTPIN (-2600 3775) $PN AG74
J 0
(-2590 3785);
DISPLAY 0.617021 (-2590 3785);
PAINT ORANGE (-2590 3785);
FORCEPROP 2 LASTPIN (-2600 3725) $PN AG76
J 0
(-2590 3735);
DISPLAY 0.617021 (-2590 3735);
PAINT ORANGE (-2590 3735);
FORCEPROP 2 LASTPIN (-2600 3675) $PN AG78
J 0
(-2590 3685);
DISPLAY 0.617021 (-2590 3685);
PAINT ORANGE (-2590 3685);
FORCEPROP 2 LASTPIN (-2600 3625) $PN AG80
J 0
(-2590 3635);
DISPLAY 0.617021 (-2590 3635);
PAINT ORANGE (-2590 3635);
FORCEPROP 2 LASTPIN (-2600 3575) $PN AH1
J 0
(-2590 3585);
DISPLAY 0.617021 (-2590 3585);
PAINT ORANGE (-2590 3585);
FORCEPROP 2 LASTPIN (-2600 3525) $PN AH5
J 0
(-2590 3535);
DISPLAY 0.617021 (-2590 3535);
PAINT ORANGE (-2590 3535);
FORCEPROP 2 LASTPIN (-2600 3475) $PN AH21
J 0
(-2590 3485);
DISPLAY 0.617021 (-2590 3485);
PAINT ORANGE (-2590 3485);
FORCEPROP 2 LASTPIN (-2600 3425) $PN AH27
J 0
(-2590 3435);
DISPLAY 0.617021 (-2590 3435);
PAINT ORANGE (-2590 3435);
FORCEPROP 2 LASTPIN (-2600 3375) $PN AH33
J 0
(-2590 3385);
DISPLAY 0.617021 (-2590 3385);
PAINT ORANGE (-2590 3385);
FORCEPROP 2 LASTPIN (-2600 3325) $PN AH35
J 0
(-2590 3335);
DISPLAY 0.617021 (-2590 3335);
PAINT ORANGE (-2590 3335);
FORCEPROP 2 LASTPIN (-2600 3275) $PN AH45
J 0
(-2590 3285);
DISPLAY 0.617021 (-2590 3285);
PAINT ORANGE (-2590 3285);
FORCEPROP 2 LASTPIN (-2600 3225) $PN AH47
J 0
(-2590 3235);
DISPLAY 0.617021 (-2590 3235);
PAINT ORANGE (-2590 3235);
FORCEPROP 2 LASTPIN (-2600 3175) $PN AH49
J 0
(-2590 3185);
DISPLAY 0.617021 (-2590 3185);
PAINT ORANGE (-2590 3185);
FORCEPROP 2 LASTPIN (-2600 3125) $PN AH51
J 0
(-2590 3135);
DISPLAY 0.617021 (-2590 3135);
PAINT ORANGE (-2590 3135);
FORCEPROP 2 LASTPIN (-2600 3075) $PN AH53
J 0
(-2590 3085);
DISPLAY 0.617021 (-2590 3085);
PAINT ORANGE (-2590 3085);
FORCEPROP 2 LASTPIN (-2600 3025) $PN AH59
J 0
(-2590 3035);
DISPLAY 0.617021 (-2590 3035);
PAINT ORANGE (-2590 3035);
FORCEPROP 2 LASTPIN (-2600 2975) $PN AH61
J 0
(-2590 2985);
DISPLAY 0.617021 (-2590 2985);
PAINT ORANGE (-2590 2985);
FORCEPROP 2 LASTPIN (-2600 2925) $PN AH65
J 0
(-2590 2935);
DISPLAY 0.617021 (-2590 2935);
PAINT ORANGE (-2590 2935);
FORCEPROP 2 LASTPIN (-2600 2875) $PN AH69
J 0
(-2590 2885);
DISPLAY 0.617021 (-2590 2885);
PAINT ORANGE (-2590 2885);
FORCEPROP 2 LASTPIN (-2600 2825) $PN AH75
J 0
(-2590 2835);
DISPLAY 0.617021 (-2590 2835);
PAINT ORANGE (-2590 2835);
FORCEPROP 2 LASTPIN (-2600 2775) $PN AH77
J 0
(-2590 2785);
DISPLAY 0.617021 (-2590 2785);
PAINT ORANGE (-2590 2785);
FORCEPROP 2 LASTPIN (-2600 2725) $PN AH83
J 0
(-2590 2735);
DISPLAY 0.617021 (-2590 2735);
PAINT ORANGE (-2590 2735);
FORCEPROP 2 LASTPIN (-2600 2675) $PN AJ8
J 0
(-2590 2685);
DISPLAY 0.617021 (-2590 2685);
PAINT ORANGE (-2590 2685);
FORCEPROP 2 LASTPIN (-2600 2625) $PN AJ22
J 0
(-2590 2635);
DISPLAY 0.617021 (-2590 2635);
PAINT ORANGE (-2590 2635);
FORCEPROP 2 LASTPIN (-2600 2575) $PN AJ26
J 0
(-2590 2585);
DISPLAY 0.617021 (-2590 2585);
PAINT ORANGE (-2590 2585);
FORCEPROP 2 LASTPIN (-2600 2525) $PN AJ28
J 0
(-2590 2535);
DISPLAY 0.617021 (-2590 2535);
PAINT ORANGE (-2590 2535);
FORCEPROP 2 LASTPIN (-2600 2475) $PN AJ32
J 0
(-2590 2485);
DISPLAY 0.617021 (-2590 2485);
PAINT ORANGE (-2590 2485);
FORCEPROP 2 LASTPIN (-2600 2425) $PN AJ34
J 0
(-2590 2435);
DISPLAY 0.617021 (-2590 2435);
PAINT ORANGE (-2590 2435);
FORCEPROP 2 LASTPIN (-2600 2375) $PN AJ46
J 0
(-2590 2385);
DISPLAY 0.617021 (-2590 2385);
PAINT ORANGE (-2590 2385);
FORCEPROP 2 LASTPIN (-2600 2325) $PN AJ48
J 0
(-2590 2335);
DISPLAY 0.617021 (-2590 2335);
PAINT ORANGE (-2590 2335);
FORCEPROP 2 LASTPIN (-2600 2275) $PN AJ50
J 0
(-2590 2285);
DISPLAY 0.617021 (-2590 2285);
PAINT ORANGE (-2590 2285);
FORCEPROP 2 LASTPIN (-2600 2225) $PN AJ52
J 0
(-2590 2235);
DISPLAY 0.617021 (-2590 2235);
PAINT ORANGE (-2590 2235);
FORCEPROP 2 LASTPIN (-2600 2175) $PN AJ54
J 0
(-2590 2185);
DISPLAY 0.617021 (-2590 2185);
PAINT ORANGE (-2590 2185);
FORCEPROP 2 LASTPIN (-2600 2125) $PN AJ66
J 0
(-2590 2135);
DISPLAY 0.617021 (-2590 2135);
PAINT ORANGE (-2590 2135);
FORCEPROP 2 LASTPIN (-2600 2075) $PN AJ68
J 0
(-2590 2085);
DISPLAY 0.617021 (-2590 2085);
PAINT ORANGE (-2590 2085);
FORCEPROP 2 LASTPIN (-2600 2025) $PN AJ74
J 0
(-2590 2035);
DISPLAY 0.617021 (-2590 2035);
PAINT ORANGE (-2590 2035);
FORCEPROP 2 LASTPIN (-2600 1975) $PN AJ78
J 0
(-2590 1985);
DISPLAY 0.617021 (-2590 1985);
PAINT ORANGE (-2590 1985);
FORCEPROP 2 LASTPIN (-2600 1925) $PN AJ82
J 0
(-2590 1935);
DISPLAY 0.617021 (-2590 1935);
PAINT ORANGE (-2590 1935);
FORCEPROP 2 LASTPIN (-2600 1875) $PN AJ86
J 0
(-2590 1885);
DISPLAY 0.617021 (-2590 1885);
PAINT ORANGE (-2590 1885);
FORCEPROP 2 LASTPIN (-2600 1825) $PN AK9
J 0
(-2590 1835);
DISPLAY 0.617021 (-2590 1835);
PAINT ORANGE (-2590 1835);
FORCEPROP 2 LASTPIN (-2600 1775) $PN AK13
J 0
(-2590 1785);
DISPLAY 0.617021 (-2590 1785);
PAINT ORANGE (-2590 1785);
FORCEPROP 2 LASTPIN (-2600 1725) $PN AK19
J 0
(-2590 1735);
DISPLAY 0.617021 (-2590 1735);
PAINT ORANGE (-2590 1735);
FORCEPROP 2 LASTPIN (-2600 1675) $PN AK23
J 0
(-2590 1685);
DISPLAY 0.617021 (-2590 1685);
PAINT ORANGE (-2590 1685);
FORCEPROP 2 LASTPIN (-2600 1625) $PN AK25
J 0
(-2590 1635);
DISPLAY 0.617021 (-2590 1635);
PAINT ORANGE (-2590 1635);
FORCEPROP 2 LASTPIN (-2600 1575) $PN AK29
J 0
(-2590 1585);
DISPLAY 0.617021 (-2590 1585);
PAINT ORANGE (-2590 1585);
FORCEPROP 2 LASTPIN (-2600 1525) $PN AK31
J 0
(-2590 1535);
DISPLAY 0.617021 (-2590 1535);
PAINT ORANGE (-2590 1535);
FORCEPROP 2 LASTPIN (-2600 1475) $PN AK33
J 0
(-2590 1485);
DISPLAY 0.617021 (-2590 1485);
PAINT ORANGE (-2590 1485);
FORCEPROP 2 LASTPIN (-2600 1425) $PN AK55
J 0
(-2590 1435);
DISPLAY 0.617021 (-2590 1435);
PAINT ORANGE (-2590 1435);
FORCEPROP 2 LASTPIN (-2600 1375) $PN AK65
J 0
(-2590 1385);
DISPLAY 0.617021 (-2590 1385);
PAINT ORANGE (-2590 1385);
FORCEPROP 2 LASTPIN (-2600 1325) $PN AK67
J 0
(-2590 1335);
DISPLAY 0.617021 (-2590 1335);
PAINT ORANGE (-2590 1335);
FORCEPROP 2 LASTPIN (-2600 1275) $PN AK73
J 0
(-2590 1285);
DISPLAY 0.617021 (-2590 1285);
PAINT ORANGE (-2590 1285);
FORCEPROP 2 LASTPIN (-2600 1225) $PN AK79
J 0
(-2590 1235);
DISPLAY 0.617021 (-2590 1235);
PAINT ORANGE (-2590 1235);
FORCEPROP 2 LASTPIN (-2600 1175) $PN AK81
J 0
(-2590 1185);
DISPLAY 0.617021 (-2590 1185);
PAINT ORANGE (-2590 1185);
FORCEPROP 2 LASTPIN (-2600 1125) $PN AK83
J 0
(-2590 1135);
DISPLAY 0.617021 (-2590 1135);
PAINT ORANGE (-2590 1135);
FORCEPROP 2 LASTPIN (-2600 1075) $PN AK85
J 0
(-2590 1085);
DISPLAY 0.617021 (-2590 1085);
PAINT ORANGE (-2590 1085);
FORCEPROP 2 LASTPIN (-2600 1025) $PN AL4
J 0
(-2590 1035);
DISPLAY 0.617021 (-2590 1035);
PAINT ORANGE (-2590 1035);
FORCEPROP 2 LASTPIN (-2600 975) $PN AL10
J 0
(-2590 985);
DISPLAY 0.617021 (-2590 985);
PAINT ORANGE (-2590 985);
FORCEPROP 2 LASTPIN (-2600 925) $PN AL24
J 0
(-2590 935);
DISPLAY 0.617021 (-2590 935);
PAINT ORANGE (-2590 935);
FORCEPROP 2 LASTPIN (-2600 875) $PN AL30
J 0
(-2590 885);
DISPLAY 0.617021 (-2590 885);
PAINT ORANGE (-2590 885);
FORCEPROP 2 LASTPIN (-2600 825) $PN AL32
J 0
(-2590 835);
DISPLAY 0.617021 (-2590 835);
PAINT ORANGE (-2590 835);
FORCEPROP 2 LASTPIN (-2600 775) $PN AL56
J 0
(-2590 785);
DISPLAY 0.617021 (-2590 785);
PAINT ORANGE (-2590 785);
FORCEPROP 2 LASTPIN (-2600 725) $PN AL64
J 0
(-2590 735);
DISPLAY 0.617021 (-2590 735);
PAINT ORANGE (-2590 735);
FORCEPROP 2 LASTPIN (-2600 675) $PN AL68
J 0
(-2590 685);
DISPLAY 0.617021 (-2590 685);
PAINT ORANGE (-2590 685);
FORCEPROP 2 LASTPIN (-2600 4525) $PN AF31
J 0
(-2590 4535);
DISPLAY 0.617021 (-2590 4535);
PAINT ORANGE (-2590 4535);
FORCEPROP 1 LAST PACK_TYPE BGA1
J 0
(-3750 4925);
PAINT SKYBLUE (-3750 4925);
DISPLAY INVISIBLE (-3750 4925);
FORCEPROP 2 LAST SEC_TYPE BGA1
J 0
(-3750 4925);
DISPLAY 1.021277 (-3750 4925);
PAINT ORANGE (-3750 4925);
DISPLAY INVISIBLE (-3750 4925);
FORCEPROP 2 LAST CDS_LIB chpset_lib
J 0
(-3200 2625);
PAINT ORANGE (-3200 2625);
DISPLAY INVISIBLE (-3200 2625);
FORCEPROP 2 LAST SEC 25
J 0
(-3750 4925);
DISPLAY 0.680851 (-3750 4925);
PAINT MONO (-3750 4925);
DISPLAY INVISIBLE (-3750 4925);
FORCEPROP 2 LAST CDS_LOCATION U2D1
J 0
(-3750 4875);
DISPLAY 0.617021 (-3750 4875);
PAINT AQUA (-3750 4875);
DISPLAY INVISIBLE (-3750 4875);
FORCEPROP 1 LAST PATH I22
J 0
(-3200 4825);
PAINT GREEN (-3200 4825);
DISPLAY INVISIBLE (-3200 4825);
FORCEADD SKX_EXT_B..26
(-1275 2600);
FORCEPROP 1 LAST LOCATION U2D1
J 0
(-1825 4850);
DISPLAY 0.617021 (-1825 4850);
PAINT AQUA (-1825 4850);
FORCEPROP 1 LAST PART_NUMBER TBD
J 0
(-1825 450);
DISPLAY 0.617021 (-1825 450);
PAINT BLUE (-1825 450);
FORCEPROP 1 LAST MATERIAL IC
J 0
(-1825 4800);
DISPLAY 0.617021 (-1825 4800);
PAINT SKYBLUE (-1825 4800);
FORCEPROP 2 LASTPIN (-1875 4600) $PN AL76
J 2
(-1885 4610);
DISPLAY 0.617021 (-1885 4610);
PAINT ORANGE (-1885 4610);
FORCEPROP 2 LASTPIN (-1875 4550) $PN AL78
J 2
(-1885 4560);
DISPLAY 0.617021 (-1885 4560);
PAINT ORANGE (-1885 4560);
FORCEPROP 2 LASTPIN (-1875 4500) $PN AL80
J 2
(-1885 4510);
DISPLAY 0.617021 (-1885 4510);
PAINT ORANGE (-1885 4510);
FORCEPROP 2 LASTPIN (-1875 4450) $PN AL82
J 2
(-1885 4460);
DISPLAY 0.617021 (-1885 4460);
PAINT ORANGE (-1885 4460);
FORCEPROP 2 LASTPIN (-1875 4400) $PN AL86
J 2
(-1885 4410);
DISPLAY 0.617021 (-1885 4410);
PAINT ORANGE (-1885 4410);
FORCEPROP 2 LASTPIN (-1875 4350) $PN AM1
J 2
(-1885 4360);
DISPLAY 0.617021 (-1885 4360);
PAINT ORANGE (-1885 4360);
FORCEPROP 2 LASTPIN (-1875 4300) $PN AC50
J 2
(-1885 4310);
DISPLAY 0.617021 (-1885 4310);
PAINT ORANGE (-1885 4310);
FORCEPROP 2 LASTPIN (-1875 4250) $PN AM31
J 2
(-1885 4260);
DISPLAY 0.617021 (-1885 4260);
PAINT ORANGE (-1885 4260);
FORCEPROP 2 LASTPIN (-1875 4200) $PN AM57
J 2
(-1885 4210);
DISPLAY 0.617021 (-1885 4210);
PAINT ORANGE (-1885 4210);
FORCEPROP 2 LASTPIN (-1875 4150) $PN AM63
J 2
(-1885 4160);
DISPLAY 0.617021 (-1885 4160);
PAINT ORANGE (-1885 4160);
FORCEPROP 2 LASTPIN (-1875 4100) $PN AM69
J 2
(-1885 4110);
DISPLAY 0.617021 (-1885 4110);
PAINT ORANGE (-1885 4110);
FORCEPROP 2 LASTPIN (-1875 4050) $PN AM73
J 2
(-1885 4060);
DISPLAY 0.617021 (-1885 4060);
PAINT ORANGE (-1885 4060);
FORCEPROP 2 LASTPIN (-1875 4000) $PN AM79
J 2
(-1885 4010);
DISPLAY 0.617021 (-1885 4010);
PAINT ORANGE (-1885 4010);
FORCEPROP 2 LASTPIN (-1875 3950) $PN AM83
J 2
(-1885 3960);
DISPLAY 0.617021 (-1885 3960);
PAINT ORANGE (-1885 3960);
FORCEPROP 2 LASTPIN (-1875 3900) $PN AN2
J 2
(-1885 3910);
DISPLAY 0.617021 (-1885 3910);
PAINT ORANGE (-1885 3910);
FORCEPROP 2 LASTPIN (-1875 3850) $PN AN6
J 2
(-1885 3860);
DISPLAY 0.617021 (-1885 3860);
PAINT ORANGE (-1885 3860);
FORCEPROP 2 LASTPIN (-1875 3800) $PN AN28
J 2
(-1885 3810);
DISPLAY 0.617021 (-1885 3810);
PAINT ORANGE (-1885 3810);
FORCEPROP 2 LASTPIN (-1875 3750) $PN AN58
J 2
(-1885 3760);
DISPLAY 0.617021 (-1885 3760);
PAINT ORANGE (-1885 3760);
FORCEPROP 2 LASTPIN (-1875 3700) $PN AN78
J 2
(-1885 3710);
DISPLAY 0.617021 (-1885 3710);
PAINT ORANGE (-1885 3710);
FORCEPROP 2 LASTPIN (-1875 3650) $PN AP5
J 2
(-1885 3660);
DISPLAY 0.617021 (-1885 3660);
PAINT ORANGE (-1885 3660);
FORCEPROP 2 LASTPIN (-1875 3600) $PN AP9
J 2
(-1885 3610);
DISPLAY 0.617021 (-1885 3610);
PAINT ORANGE (-1885 3610);
FORCEPROP 2 LASTPIN (-1875 3550) $PN AP13
J 2
(-1885 3560);
DISPLAY 0.617021 (-1885 3560);
PAINT ORANGE (-1885 3560);
FORCEPROP 2 LASTPIN (-1875 3500) $PN AP19
J 2
(-1885 3510);
DISPLAY 0.617021 (-1885 3510);
PAINT ORANGE (-1885 3510);
FORCEPROP 2 LASTPIN (-1875 3450) $PN AP31
J 2
(-1885 3460);
DISPLAY 0.617021 (-1885 3460);
PAINT ORANGE (-1885 3460);
FORCEPROP 2 LASTPIN (-1875 3400) $PN AP59
J 2
(-1885 3410);
DISPLAY 0.617021 (-1885 3410);
PAINT ORANGE (-1885 3410);
FORCEPROP 2 LASTPIN (-1875 3350) $PN AP63
J 2
(-1885 3360);
DISPLAY 0.617021 (-1885 3360);
PAINT ORANGE (-1885 3360);
FORCEPROP 2 LASTPIN (-1875 3300) $PN AP65
J 2
(-1885 3310);
DISPLAY 0.617021 (-1885 3310);
PAINT ORANGE (-1885 3310);
FORCEPROP 2 LASTPIN (-1875 3250) $PN AP67
J 2
(-1885 3260);
DISPLAY 0.617021 (-1885 3260);
PAINT ORANGE (-1885 3260);
FORCEPROP 2 LASTPIN (-1875 3200) $PN AP69
J 2
(-1885 3210);
DISPLAY 0.617021 (-1885 3210);
PAINT ORANGE (-1885 3210);
FORCEPROP 2 LASTPIN (-1875 3150) $PN AP73
J 2
(-1885 3160);
DISPLAY 0.617021 (-1885 3160);
PAINT ORANGE (-1885 3160);
FORCEPROP 2 LASTPIN (-1875 3100) $PN AP75
J 2
(-1885 3110);
DISPLAY 0.617021 (-1885 3110);
PAINT ORANGE (-1885 3110);
FORCEPROP 2 LASTPIN (-1875 3050) $PN AP81
J 2
(-1885 3060);
DISPLAY 0.617021 (-1885 3060);
PAINT ORANGE (-1885 3060);
FORCEPROP 2 LASTPIN (-1875 3000) $PN AP83
J 2
(-1885 3010);
DISPLAY 0.617021 (-1885 3010);
PAINT ORANGE (-1885 3010);
FORCEPROP 2 LASTPIN (-1875 2950) $PN AP85
J 2
(-1885 2960);
DISPLAY 0.617021 (-1885 2960);
PAINT ORANGE (-1885 2960);
FORCEPROP 2 LASTPIN (-1875 2900) $PN AR10
J 2
(-1885 2910);
DISPLAY 0.617021 (-1885 2910);
PAINT ORANGE (-1885 2910);
FORCEPROP 2 LASTPIN (-1875 2850) $PN AR24
J 2
(-1885 2860);
DISPLAY 0.617021 (-1885 2860);
PAINT ORANGE (-1885 2860);
FORCEPROP 2 LASTPIN (-1875 2800) $PN AR30
J 2
(-1885 2810);
DISPLAY 0.617021 (-1885 2810);
PAINT ORANGE (-1885 2810);
FORCEPROP 2 LASTPIN (-1875 2750) $PN AR60
J 2
(-1885 2760);
DISPLAY 0.617021 (-1885 2760);
PAINT ORANGE (-1885 2760);
FORCEPROP 2 LASTPIN (-1875 2700) $PN AR72
J 2
(-1885 2710);
DISPLAY 0.617021 (-1885 2710);
PAINT ORANGE (-1885 2710);
FORCEPROP 2 LASTPIN (-1875 2650) $PN AR78
J 2
(-1885 2660);
DISPLAY 0.617021 (-1885 2660);
PAINT ORANGE (-1885 2660);
FORCEPROP 2 LASTPIN (-1875 2550) $PN P63
J 2
(-1885 2560);
DISPLAY 0.617021 (-1885 2560);
PAINT ORANGE (-1885 2560);
FORCEPROP 2 LASTPIN (-1875 2500) $PN AT15
J 2
(-1885 2510);
DISPLAY 0.617021 (-1885 2510);
PAINT ORANGE (-1885 2510);
FORCEPROP 2 LASTPIN (-1875 2450) $PN AT17
J 2
(-1885 2460);
DISPLAY 0.617021 (-1885 2460);
PAINT ORANGE (-1885 2460);
FORCEPROP 2 LASTPIN (-1875 2400) $PN AT21
J 2
(-1885 2410);
DISPLAY 0.617021 (-1885 2410);
PAINT ORANGE (-1885 2410);
FORCEPROP 2 LASTPIN (-1875 2350) $PN AT27
J 2
(-1885 2360);
DISPLAY 0.617021 (-1885 2360);
PAINT ORANGE (-1885 2360);
FORCEPROP 2 LASTPIN (-1875 2300) $PN AT61
J 2
(-1885 2310);
DISPLAY 0.617021 (-1885 2310);
PAINT ORANGE (-1885 2310);
FORCEPROP 2 LASTPIN (-1875 2200) $PN AT69
J 2
(-1885 2210);
DISPLAY 0.617021 (-1885 2210);
PAINT ORANGE (-1885 2210);
FORCEPROP 2 LASTPIN (-1875 2150) $PN AT73
J 2
(-1885 2160);
DISPLAY 0.617021 (-1885 2160);
PAINT ORANGE (-1885 2160);
FORCEPROP 2 LASTPIN (-1875 2100) $PN AT77
J 2
(-1885 2110);
DISPLAY 0.617021 (-1885 2110);
PAINT ORANGE (-1885 2110);
FORCEPROP 2 LASTPIN (-1875 2050) $PN AT83
J 2
(-1885 2060);
DISPLAY 0.617021 (-1885 2060);
PAINT ORANGE (-1885 2060);
FORCEPROP 2 LASTPIN (-1875 2000) $PN AT85
J 2
(-1885 2010);
DISPLAY 0.617021 (-1885 2010);
PAINT ORANGE (-1885 2010);
FORCEPROP 2 LASTPIN (-1875 1950) $PN AU2
J 2
(-1885 1960);
DISPLAY 0.617021 (-1885 1960);
PAINT ORANGE (-1885 1960);
FORCEPROP 2 LASTPIN (-1875 1900) $PN AU6
J 2
(-1885 1910);
DISPLAY 0.617021 (-1885 1910);
PAINT ORANGE (-1885 1910);
FORCEPROP 2 LASTPIN (-1875 1850) $PN AU26
J 2
(-1885 1860);
DISPLAY 0.617021 (-1885 1860);
PAINT ORANGE (-1885 1860);
FORCEPROP 2 LASTPIN (-1875 1800) $PN AU28
J 2
(-1885 1810);
DISPLAY 0.617021 (-1885 1810);
PAINT ORANGE (-1885 1810);
FORCEPROP 2 LASTPIN (-1875 1700) $PN AU64
J 2
(-1885 1710);
DISPLAY 0.617021 (-1885 1710);
PAINT ORANGE (-1885 1710);
FORCEPROP 2 LASTPIN (-1875 1650) $PN AU68
J 2
(-1885 1660);
DISPLAY 0.617021 (-1885 1660);
PAINT ORANGE (-1885 1660);
FORCEPROP 2 LASTPIN (-1875 1600) $PN AU74
J 2
(-1885 1610);
DISPLAY 0.617021 (-1885 1610);
PAINT ORANGE (-1885 1610);
FORCEPROP 2 LASTPIN (-1875 1550) $PN AU76
J 2
(-1885 1560);
DISPLAY 0.617021 (-1885 1560);
PAINT ORANGE (-1885 1560);
FORCEPROP 2 LASTPIN (-1875 1500) $PN AU78
J 2
(-1885 1510);
DISPLAY 0.617021 (-1885 1510);
PAINT ORANGE (-1885 1510);
FORCEPROP 2 LASTPIN (-1875 1450) $PN AU80
J 2
(-1885 1460);
DISPLAY 0.617021 (-1885 1460);
PAINT ORANGE (-1885 1460);
FORCEPROP 2 LASTPIN (-1875 1400) $PN AU84
J 2
(-1885 1410);
DISPLAY 0.617021 (-1885 1410);
PAINT ORANGE (-1885 1410);
FORCEPROP 2 LASTPIN (-1875 1350) $PN AU86
J 2
(-1885 1360);
DISPLAY 0.617021 (-1885 1360);
PAINT ORANGE (-1885 1360);
FORCEPROP 2 LASTPIN (-1875 1300) $PN AV1
J 2
(-1885 1310);
DISPLAY 0.617021 (-1885 1310);
PAINT ORANGE (-1885 1310);
FORCEPROP 2 LASTPIN (-1875 1250) $PN AV3
J 2
(-1885 1260);
DISPLAY 0.617021 (-1885 1260);
PAINT ORANGE (-1885 1260);
FORCEPROP 2 LASTPIN (-1875 1200) $PN AV7
J 2
(-1885 1210);
DISPLAY 0.617021 (-1885 1210);
PAINT ORANGE (-1885 1210);
FORCEPROP 2 LASTPIN (-1875 1150) $PN AV11
J 2
(-1885 1160);
DISPLAY 0.617021 (-1885 1160);
PAINT ORANGE (-1885 1160);
FORCEPROP 2 LASTPIN (-1875 1100) $PN AV13
J 2
(-1885 1110);
DISPLAY 0.617021 (-1885 1110);
PAINT ORANGE (-1885 1110);
FORCEPROP 2 LASTPIN (-1875 1050) $PN AV19
J 2
(-1885 1060);
DISPLAY 0.617021 (-1885 1060);
PAINT ORANGE (-1885 1060);
FORCEPROP 2 LASTPIN (-1875 1000) $PN AV23
J 2
(-1885 1010);
DISPLAY 0.617021 (-1885 1010);
PAINT ORANGE (-1885 1010);
FORCEPROP 2 LASTPIN (-1875 950) $PN AV25
J 2
(-1885 960);
DISPLAY 0.617021 (-1885 960);
PAINT ORANGE (-1885 960);
FORCEPROP 2 LASTPIN (-1875 900) $PN AV63
J 2
(-1885 910);
DISPLAY 0.617021 (-1885 910);
PAINT ORANGE (-1885 910);
FORCEPROP 2 LASTPIN (-1875 850) $PN AV65
J 2
(-1885 860);
DISPLAY 0.617021 (-1885 860);
PAINT ORANGE (-1885 860);
FORCEPROP 2 LASTPIN (-1875 800) $PN AV67
J 2
(-1885 810);
DISPLAY 0.617021 (-1885 810);
PAINT ORANGE (-1885 810);
FORCEPROP 2 LASTPIN (-1875 750) $PN AV75
J 2
(-1885 760);
DISPLAY 0.617021 (-1885 760);
PAINT ORANGE (-1885 760);
FORCEPROP 2 LASTPIN (-1875 700) $PN AV83
J 2
(-1885 710);
DISPLAY 0.617021 (-1885 710);
PAINT ORANGE (-1885 710);
FORCEPROP 2 LASTPIN (-1875 650) $PN AW2
J 2
(-1885 660);
DISPLAY 0.617021 (-1885 660);
PAINT ORANGE (-1885 660);
FORCEPROP 2 LASTPIN (-675 4600) $PN AW10
J 0
(-665 4610);
DISPLAY 0.617021 (-665 4610);
PAINT ORANGE (-665 4610);
FORCEPROP 2 LASTPIN (-675 4550) $PN AW62
J 0
(-665 4560);
DISPLAY 0.617021 (-665 4560);
PAINT ORANGE (-665 4560);
FORCEPROP 2 LASTPIN (-675 4500) $PN AW66
J 0
(-665 4510);
DISPLAY 0.617021 (-665 4510);
PAINT ORANGE (-665 4510);
FORCEPROP 2 LASTPIN (-675 4450) $PN AW68
J 0
(-665 4460);
DISPLAY 0.617021 (-665 4460);
PAINT ORANGE (-665 4460);
FORCEPROP 2 LASTPIN (-675 4400) $PN AW70
J 0
(-665 4410);
DISPLAY 0.617021 (-665 4410);
PAINT ORANGE (-665 4410);
FORCEPROP 2 LASTPIN (-675 4350) $PN AW72
J 0
(-665 4360);
DISPLAY 0.617021 (-665 4360);
PAINT ORANGE (-665 4360);
FORCEPROP 2 LASTPIN (-675 4300) $PN AW74
J 0
(-665 4310);
DISPLAY 0.617021 (-665 4310);
PAINT ORANGE (-665 4310);
FORCEPROP 2 LASTPIN (-675 4250) $PN AW78
J 0
(-665 4260);
DISPLAY 0.617021 (-665 4260);
PAINT ORANGE (-665 4260);
FORCEPROP 2 LASTPIN (-675 4200) $PN AW82
J 0
(-665 4210);
DISPLAY 0.617021 (-665 4210);
PAINT ORANGE (-665 4210);
FORCEPROP 2 LASTPIN (-675 4150) $PN AW84
J 0
(-665 4160);
DISPLAY 0.617021 (-665 4160);
PAINT ORANGE (-665 4160);
FORCEPROP 2 LASTPIN (-675 4100) $PN AY5
J 0
(-665 4110);
DISPLAY 0.617021 (-665 4110);
PAINT ORANGE (-665 4110);
FORCEPROP 2 LASTPIN (-675 4050) $PN AY15
J 0
(-665 4060);
DISPLAY 0.617021 (-665 4060);
PAINT ORANGE (-665 4060);
FORCEPROP 2 LASTPIN (-675 4000) $PN AY17
J 0
(-665 4010);
DISPLAY 0.617021 (-665 4010);
PAINT ORANGE (-665 4010);
FORCEPROP 2 LASTPIN (-675 3950) $PN AY21
J 0
(-665 3960);
DISPLAY 0.617021 (-665 3960);
PAINT ORANGE (-665 3960);
FORCEPROP 2 LASTPIN (-675 3900) $PN AY23
J 0
(-665 3910);
DISPLAY 0.617021 (-665 3910);
PAINT ORANGE (-665 3910);
FORCEPROP 2 LASTPIN (-675 3850) $PN AY25
J 0
(-665 3860);
DISPLAY 0.617021 (-665 3860);
PAINT ORANGE (-665 3860);
FORCEPROP 2 LASTPIN (-675 3800) $PN AY63
J 0
(-665 3810);
DISPLAY 0.617021 (-665 3810);
PAINT ORANGE (-665 3810);
FORCEPROP 2 LASTPIN (-675 3750) $PN AY79
J 0
(-665 3760);
DISPLAY 0.617021 (-665 3760);
PAINT ORANGE (-665 3760);
FORCEPROP 2 LASTPIN (-675 3700) $PN AY81
J 0
(-665 3710);
DISPLAY 0.617021 (-665 3710);
PAINT ORANGE (-665 3710);
FORCEPROP 2 LASTPIN (-675 3650) $PN BA2
J 0
(-665 3660);
DISPLAY 0.617021 (-665 3660);
PAINT ORANGE (-665 3660);
FORCEPROP 2 LASTPIN (-675 3600) $PN BA6
J 0
(-665 3610);
DISPLAY 0.617021 (-665 3610);
PAINT ORANGE (-665 3610);
FORCEPROP 2 LASTPIN (-675 3550) $PN BA12
J 0
(-665 3560);
DISPLAY 0.617021 (-665 3560);
PAINT ORANGE (-665 3560);
FORCEPROP 2 LASTPIN (-675 3500) $PN BA62
J 0
(-665 3510);
DISPLAY 0.617021 (-665 3510);
PAINT ORANGE (-665 3510);
FORCEPROP 2 LASTPIN (-675 3450) $PN BA68
J 0
(-665 3460);
DISPLAY 0.617021 (-665 3460);
PAINT ORANGE (-665 3460);
FORCEPROP 2 LASTPIN (-675 3350) $PN BA80
J 0
(-665 3360);
DISPLAY 0.617021 (-665 3360);
PAINT ORANGE (-665 3360);
FORCEPROP 2 LASTPIN (-675 3300) $PN BA84
J 0
(-665 3310);
DISPLAY 0.617021 (-665 3310);
PAINT ORANGE (-665 3310);
FORCEPROP 2 LASTPIN (-675 3250) $PN BB19
J 0
(-665 3260);
DISPLAY 0.617021 (-665 3260);
PAINT ORANGE (-665 3260);
FORCEPROP 2 LASTPIN (-675 3200) $PN BB23
J 0
(-665 3210);
DISPLAY 0.617021 (-665 3210);
PAINT ORANGE (-665 3210);
FORCEPROP 2 LASTPIN (-675 3150) $PN BB63
J 0
(-665 3160);
DISPLAY 0.617021 (-665 3160);
PAINT ORANGE (-665 3160);
FORCEPROP 2 LASTPIN (-675 3100) $PN BB69
J 0
(-665 3110);
DISPLAY 0.617021 (-665 3110);
PAINT ORANGE (-665 3110);
FORCEPROP 2 LASTPIN (-675 3050) $PN BB73
J 0
(-665 3060);
DISPLAY 0.617021 (-665 3060);
PAINT ORANGE (-665 3060);
FORCEPROP 2 LASTPIN (-675 3000) $PN BB75
J 0
(-665 3010);
DISPLAY 0.617021 (-665 3010);
PAINT ORANGE (-665 3010);
FORCEPROP 2 LASTPIN (-675 2950) $PN BB77
J 0
(-665 2960);
DISPLAY 0.617021 (-665 2960);
PAINT ORANGE (-665 2960);
FORCEPROP 2 LASTPIN (-675 2900) $PN BB79
J 0
(-665 2910);
DISPLAY 0.617021 (-665 2910);
PAINT ORANGE (-665 2910);
FORCEPROP 2 LASTPIN (-675 2850) $PN BB81
J 0
(-665 2860);
DISPLAY 0.617021 (-665 2860);
PAINT ORANGE (-665 2860);
FORCEPROP 2 LASTPIN (-675 2800) $PN BB83
J 0
(-665 2810);
DISPLAY 0.617021 (-665 2810);
PAINT ORANGE (-665 2810);
FORCEPROP 2 LASTPIN (-675 2750) $PN BC4
J 0
(-665 2760);
DISPLAY 0.617021 (-665 2760);
PAINT ORANGE (-665 2760);
FORCEPROP 2 LASTPIN (-675 2700) $PN BC8
J 0
(-665 2710);
DISPLAY 0.617021 (-665 2710);
PAINT ORANGE (-665 2710);
FORCEPROP 2 LASTPIN (-675 2650) $PN BC12
J 0
(-665 2660);
DISPLAY 0.617021 (-665 2660);
PAINT ORANGE (-665 2660);
FORCEPROP 2 LASTPIN (-675 2600) $PN BC16
J 0
(-665 2610);
DISPLAY 0.617021 (-665 2610);
PAINT ORANGE (-665 2610);
FORCEPROP 2 LASTPIN (-675 2550) $PN BC70
J 0
(-665 2560);
DISPLAY 0.617021 (-665 2560);
PAINT ORANGE (-665 2560);
FORCEPROP 2 LASTPIN (-675 2500) $PN BC72
J 0
(-665 2510);
DISPLAY 0.617021 (-665 2510);
PAINT ORANGE (-665 2510);
FORCEPROP 2 LASTPIN (-675 2450) $PN BC74
J 0
(-665 2460);
DISPLAY 0.617021 (-665 2460);
PAINT ORANGE (-665 2460);
FORCEPROP 2 LASTPIN (-675 2400) $PN BC76
J 0
(-665 2410);
DISPLAY 0.617021 (-665 2410);
PAINT ORANGE (-665 2410);
FORCEPROP 2 LASTPIN (-675 2350) $PN BC78
J 0
(-665 2360);
DISPLAY 0.617021 (-665 2360);
PAINT ORANGE (-665 2360);
FORCEPROP 2 LASTPIN (-675 2300) $PN BC80
J 0
(-665 2310);
DISPLAY 0.617021 (-665 2310);
PAINT ORANGE (-665 2310);
FORCEPROP 2 LASTPIN (-675 2250) $PN BC82
J 0
(-665 2260);
DISPLAY 0.617021 (-665 2260);
PAINT ORANGE (-665 2260);
FORCEPROP 2 LASTPIN (-675 2200) $PN BD5
J 0
(-665 2210);
DISPLAY 0.617021 (-665 2210);
PAINT ORANGE (-665 2210);
FORCEPROP 2 LASTPIN (-675 2150) $PN BD11
J 0
(-665 2160);
DISPLAY 0.617021 (-665 2160);
PAINT ORANGE (-665 2160);
FORCEPROP 2 LASTPIN (-675 2100) $PN BD15
J 0
(-665 2110);
DISPLAY 0.617021 (-665 2110);
PAINT ORANGE (-665 2110);
FORCEPROP 2 LASTPIN (-675 2050) $PN BD21
J 0
(-665 2060);
DISPLAY 0.617021 (-665 2060);
PAINT ORANGE (-665 2060);
FORCEPROP 2 LASTPIN (-675 2000) $PN BD27
J 0
(-665 2010);
DISPLAY 0.617021 (-665 2010);
PAINT ORANGE (-665 2010);
FORCEPROP 2 LASTPIN (-675 1950) $PN BD63
J 0
(-665 1960);
DISPLAY 0.617021 (-665 1960);
PAINT ORANGE (-665 1960);
FORCEPROP 2 LASTPIN (-675 1900) $PN BD71
J 0
(-665 1910);
DISPLAY 0.617021 (-665 1910);
PAINT ORANGE (-665 1910);
FORCEPROP 2 LASTPIN (-675 1850) $PN BE4
J 0
(-665 1860);
DISPLAY 0.617021 (-665 1860);
PAINT ORANGE (-665 1860);
FORCEPROP 2 LASTPIN (-675 1800) $PN BE6
J 0
(-665 1810);
DISPLAY 0.617021 (-665 1810);
PAINT ORANGE (-665 1810);
FORCEPROP 2 LASTPIN (-675 1750) $PN BE8
J 0
(-665 1760);
DISPLAY 0.617021 (-665 1760);
PAINT ORANGE (-665 1760);
FORCEPROP 2 LASTPIN (-675 1700) $PN BE10
J 0
(-665 1710);
DISPLAY 0.617021 (-665 1710);
PAINT ORANGE (-665 1710);
FORCEPROP 2 LASTPIN (-675 1650) $PN BE26
J 0
(-665 1660);
DISPLAY 0.617021 (-665 1660);
PAINT ORANGE (-665 1660);
FORCEPROP 2 LASTPIN (-675 1600) $PN BE64
J 0
(-665 1610);
DISPLAY 0.617021 (-665 1610);
PAINT ORANGE (-665 1610);
FORCEPROP 2 LASTPIN (-675 1550) $PN BE66
J 0
(-665 1560);
DISPLAY 0.617021 (-665 1560);
PAINT ORANGE (-665 1560);
FORCEPROP 2 LASTPIN (-675 1500) $PN BE68
J 0
(-665 1510);
DISPLAY 0.617021 (-665 1510);
PAINT ORANGE (-665 1510);
FORCEPROP 2 LASTPIN (-675 1450) $PN BE70
J 0
(-665 1460);
DISPLAY 0.617021 (-665 1460);
PAINT ORANGE (-665 1460);
FORCEPROP 2 LASTPIN (-675 1400) $PN BF9
J 0
(-665 1410);
DISPLAY 0.617021 (-665 1410);
PAINT ORANGE (-665 1410);
FORCEPROP 2 LASTPIN (-675 1350) $PN BF15
J 0
(-665 1360);
DISPLAY 0.617021 (-665 1360);
PAINT ORANGE (-665 1360);
FORCEPROP 2 LASTPIN (-675 1300) $PN BF17
J 0
(-665 1310);
DISPLAY 0.617021 (-665 1310);
PAINT ORANGE (-665 1310);
FORCEPROP 2 LASTPIN (-675 1250) $PN BF19
J 0
(-665 1260);
DISPLAY 0.617021 (-665 1260);
PAINT ORANGE (-665 1260);
FORCEPROP 2 LASTPIN (-675 1200) $PN BF25
J 0
(-665 1210);
DISPLAY 0.617021 (-665 1210);
PAINT ORANGE (-665 1210);
FORCEPROP 2 LASTPIN (-675 1150) $PN BF63
J 0
(-665 1160);
DISPLAY 0.617021 (-665 1160);
PAINT ORANGE (-665 1160);
FORCEPROP 2 LASTPIN (-675 1100) $PN BF65
J 0
(-665 1110);
DISPLAY 0.617021 (-665 1110);
PAINT ORANGE (-665 1110);
FORCEPROP 2 LASTPIN (-675 1050) $PN BF67
J 0
(-665 1060);
DISPLAY 0.617021 (-665 1060);
PAINT ORANGE (-665 1060);
FORCEPROP 2 LASTPIN (-675 1000) $PN BF69
J 0
(-665 1010);
DISPLAY 0.617021 (-665 1010);
PAINT ORANGE (-665 1010);
FORCEPROP 2 LASTPIN (-675 950) $PN BF71
J 0
(-665 960);
DISPLAY 0.617021 (-665 960);
PAINT ORANGE (-665 960);
FORCEPROP 2 LASTPIN (-675 900) $PN BG6
J 0
(-665 910);
DISPLAY 0.617021 (-665 910);
PAINT ORANGE (-665 910);
FORCEPROP 2 LASTPIN (-675 850) $PN BG8
J 0
(-665 860);
DISPLAY 0.617021 (-665 860);
PAINT ORANGE (-665 860);
FORCEPROP 2 LASTPIN (-675 800) $PN BG10
J 0
(-665 810);
DISPLAY 0.617021 (-665 810);
PAINT ORANGE (-665 810);
FORCEPROP 2 LASTPIN (-675 750) $PN BG22
J 0
(-665 760);
DISPLAY 0.617021 (-665 760);
PAINT ORANGE (-665 760);
FORCEPROP 2 LASTPIN (-675 700) $PN BG24
J 0
(-665 710);
DISPLAY 0.617021 (-665 710);
PAINT ORANGE (-665 710);
FORCEPROP 2 LASTPIN (-675 650) $PN BG72
J 0
(-665 660);
DISPLAY 0.617021 (-665 660);
PAINT ORANGE (-665 660);
FORCEPROP 2 LASTPIN (-1875 2250) $PN AT63
J 2
(-1885 2260);
DISPLAY 0.617021 (-1885 2260);
PAINT ORANGE (-1885 2260);
FORCEPROP 2 LASTPIN (-675 3400) $PN BA74
J 0
(-665 3410);
DISPLAY 0.617021 (-665 3410);
PAINT ORANGE (-665 3410);
FORCEPROP 2 LASTPIN (-1875 1750) $PN AU62
J 2
(-1885 1760);
DISPLAY 0.617021 (-1885 1760);
PAINT ORANGE (-1885 1760);
FORCEPROP 2 LASTPIN (-1875 2600) $PN AC48
J 2
(-1885 2610);
DISPLAY 0.617021 (-1885 2610);
PAINT ORANGE (-1885 2610);
FORCEPROP 1 LAST PACK_TYPE BGA1
J 0
(-1825 4900);
PAINT SKYBLUE (-1825 4900);
DISPLAY INVISIBLE (-1825 4900);
FORCEPROP 2 LAST SEC_TYPE BGA1
J 0
(-1825 4900);
DISPLAY 1.021277 (-1825 4900);
PAINT ORANGE (-1825 4900);
DISPLAY INVISIBLE (-1825 4900);
FORCEPROP 2 LAST CDS_LIB chpset_lib
J 0
(-1275 2600);
PAINT ORANGE (-1275 2600);
DISPLAY INVISIBLE (-1275 2600);
FORCEPROP 2 LAST SEC 26
J 0
(-1825 4900);
DISPLAY 0.680851 (-1825 4900);
PAINT MONO (-1825 4900);
DISPLAY INVISIBLE (-1825 4900);
FORCEPROP 2 LAST CDS_LOCATION U2D1
J 0
(-1825 4850);
DISPLAY 0.617021 (-1825 4850);
PAINT AQUA (-1825 4850);
DISPLAY INVISIBLE (-1825 4850);
FORCEPROP 1 LAST PATH I23
J 0
(-1275 4800);
PAINT GREEN (-1275 4800);
DISPLAY INVISIBLE (-1275 4800);
FORCEADD GND..1
(-6100 475);
FORCEPROP 3 LASTPIN (-6100 525) SIG_NAME GND\g
J 0
(-6090 535);
DISPLAY 0.659574 (-6090 535);
PAINT MONO (-6090 535);
DISPLAY INVISIBLE (-6090 535);
FORCEPROP 1 LAST VOLTAGE 0.0V
J 0
(-6145 432);
DISPLAY 0.340426 (-6145 432);
PAINT SKYBLUE (-6145 432);
DISPLAY INVISIBLE (-6145 432);
FORCEPROP 1 LAST SIZE 1B
J 0
(-6025 425);
DISPLAY 1.170213 (-6025 425);
PAINT AQUA (-6025 425);
DISPLAY INVISIBLE (-6025 425);
FORCEPROP 2 LAST CDS_LIB mstr_symbols
J 0
(-6100 475);
PAINT ORANGE (-6100 475);
DISPLAY INVISIBLE (-6100 475);
FORCEPROP 1 LAST BODY_TYPE PLUMBING
J 0
(-6145 432);
DISPLAY 0.340426 (-6145 432);
PAINT GREEN (-6145 432);
DISPLAY INVISIBLE (-6145 432);
FORCEPROP 1 LAST PATH I3
J 0
(-6025 475);
DISPLAY 1.170213 (-6025 475);
PAINT AQUA (-6025 475);
DISPLAY INVISIBLE (-6025 475);
FORCEPROP 1 LAST HDL_POWER GND
J 0
(-6100 625);
DISPLAY 1.170213 (-6100 625);
PAINT GREEN (-6100 625);
DISPLAY INVISIBLE (-6100 625);
FORCEADD GND..1
(-5775 500);
FORCEPROP 3 LASTPIN (-5775 550) SIG_NAME GND\g
J 0
(-5765 560);
DISPLAY 0.659574 (-5765 560);
PAINT MONO (-5765 560);
DISPLAY INVISIBLE (-5765 560);
FORCEPROP 1 LAST VOLTAGE 0.0V
J 0
(-5820 457);
DISPLAY 0.340426 (-5820 457);
PAINT SKYBLUE (-5820 457);
DISPLAY INVISIBLE (-5820 457);
FORCEPROP 1 LAST SIZE 1B
J 0
(-5700 450);
DISPLAY 1.170213 (-5700 450);
PAINT AQUA (-5700 450);
DISPLAY INVISIBLE (-5700 450);
FORCEPROP 2 LAST CDS_LIB mstr_symbols
J 0
(-5775 500);
PAINT ORANGE (-5775 500);
DISPLAY INVISIBLE (-5775 500);
FORCEPROP 1 LAST BODY_TYPE PLUMBING
J 0
(-5820 457);
DISPLAY 0.340426 (-5820 457);
PAINT GREEN (-5820 457);
DISPLAY INVISIBLE (-5820 457);
FORCEPROP 1 LAST PATH I4
J 0
(-5700 500);
DISPLAY 1.170213 (-5700 500);
PAINT AQUA (-5700 500);
DISPLAY INVISIBLE (-5700 500);
FORCEPROP 1 LAST HDL_POWER GND
J 0
(-5775 650);
DISPLAY 1.170213 (-5775 650);
PAINT GREEN (-5775 650);
DISPLAY INVISIBLE (-5775 650);
FORCEADD GND..1
(-4250 500);
FORCEPROP 3 LASTPIN (-4250 550) SIG_NAME GND\g
J 0
(-4240 560);
DISPLAY 0.659574 (-4240 560);
PAINT MONO (-4240 560);
DISPLAY INVISIBLE (-4240 560);
FORCEPROP 1 LAST VOLTAGE 0.0V
J 0
(-4295 457);
DISPLAY 0.340426 (-4295 457);
PAINT SKYBLUE (-4295 457);
DISPLAY INVISIBLE (-4295 457);
FORCEPROP 1 LAST SIZE 1B
J 0
(-4175 450);
DISPLAY 1.170213 (-4175 450);
PAINT AQUA (-4175 450);
DISPLAY INVISIBLE (-4175 450);
FORCEPROP 2 LAST CDS_LIB mstr_symbols
J 0
(-4250 500);
PAINT ORANGE (-4250 500);
DISPLAY INVISIBLE (-4250 500);
FORCEPROP 1 LAST BODY_TYPE PLUMBING
J 0
(-4295 457);
DISPLAY 0.340426 (-4295 457);
PAINT GREEN (-4295 457);
DISPLAY INVISIBLE (-4295 457);
FORCEPROP 1 LAST PATH I6
J 0
(-4175 500);
DISPLAY 1.170213 (-4175 500);
PAINT AQUA (-4175 500);
DISPLAY INVISIBLE (-4175 500);
FORCEPROP 1 LAST HDL_POWER GND
J 0
(-4250 650);
DISPLAY 1.170213 (-4250 650);
PAINT GREEN (-4250 650);
DISPLAY INVISIBLE (-4250 650);
FORCEADD GND..1
(-3950 500);
FORCEPROP 3 LASTPIN (-3950 550) SIG_NAME GND\g
J 0
(-3940 560);
DISPLAY 0.659574 (-3940 560);
PAINT MONO (-3940 560);
DISPLAY INVISIBLE (-3940 560);
FORCEPROP 1 LAST VOLTAGE 0.0V
J 0
(-3995 457);
DISPLAY 0.340426 (-3995 457);
PAINT SKYBLUE (-3995 457);
DISPLAY INVISIBLE (-3995 457);
FORCEPROP 2 LAST CDS_LIB mstr_symbols
J 0
(-3950 500);
PAINT ORANGE (-3950 500);
DISPLAY INVISIBLE (-3950 500);
FORCEPROP 1 LAST SIZE 1B
J 0
(-3875 450);
DISPLAY 1.170213 (-3875 450);
PAINT AQUA (-3875 450);
DISPLAY INVISIBLE (-3875 450);
FORCEPROP 1 LAST BODY_TYPE PLUMBING
J 0
(-3995 457);
DISPLAY 0.340426 (-3995 457);
PAINT GREEN (-3995 457);
DISPLAY INVISIBLE (-3995 457);
FORCEPROP 1 LAST PATH I9
J 0
(-3875 500);
DISPLAY 0.872340 (-3875 500);
PAINT AQUA (-3875 500);
DISPLAY INVISIBLE (-3875 500);
FORCEPROP 1 LAST HDL_POWER GND
J 0
(-3950 650);
DISPLAY 1.170213 (-3950 650);
PAINT GREEN (-3950 650);
DISPLAY INVISIBLE (-3950 650);
FORCEADD PRELIM..10
(-1265 2590);
PAINT GRAY (-1265 2590);
FORCEPROP 2 LAST CDS_LIB mstr_misc
J 0
(-1265 2590);
PAINT ORANGE (-1265 2590);
DISPLAY INVISIBLE (-1265 2590);
FORCEPROP 1 LAST COMMENT_BODY TRUE
J 0
(-1265 2590);
PAINT ORANGE (-1265 2590);
DISPLAY INVISIBLE (-1265 2590);
FORCEADD PRELIM..10
(-5015 2615);
PAINT GRAY (-5015 2615);
FORCEPROP 2 LAST CDS_LIB mstr_misc
J 0
(-5015 2615);
PAINT ORANGE (-5015 2615);
DISPLAY INVISIBLE (-5015 2615);
FORCEPROP 1 LAST COMMENT_BODY TRUE
J 0
(-5015 2615);
PAINT ORANGE (-5015 2615);
DISPLAY INVISIBLE (-5015 2615);
FORCEADD PRELIM..10
(-3190 2615);
PAINT GRAY (-3190 2615);
FORCEPROP 2 LAST CDS_LIB mstr_misc
J 0
(-3190 2615);
PAINT ORANGE (-3190 2615);
DISPLAY INVISIBLE (-3190 2615);
FORCEPROP 1 LAST COMMENT_BODY TRUE
J 0
(-3190 2615);
PAINT ORANGE (-3190 2615);
DISPLAY INVISIBLE (-3190 2615);
FORCEADD DESIGN_NOTE..1
(-6500 275);
FORCEPROP 0 LAST L1 CPU SYMBOLS 1-30 ARE PRELIMINARY AND SUBJECT TO CHANGE
J 0
(-6700 150);
DISPLAY 1.021277 (-6700 150);
PAINT ORANGE (-6700 150);
FORCEPROP 2 LAST CDS_LIB mstr_symbols
J 0
(-6500 275);
PAINT ORANGE (-6500 275);
DISPLAY INVISIBLE (-6500 275);
FORCEPROP 1 LAST COMMENT_BODY TRUE
J 0
(-6475 375);
DISPLAY 0.978723 (-6475 375);
PAINT ORANGE (-6475 375);
DISPLAY INVISIBLE (-6475 375);
FORCEADD PRELIM..10
(-6865 2615);
PAINT GRAY (-6865 2615);
FORCEPROP 2 LAST CDS_LIB mstr_misc
J 0
(-6865 2615);
PAINT ORANGE (-6865 2615);
DISPLAY INVISIBLE (-6865 2615);
FORCEPROP 1 LAST COMMENT_BODY TRUE
J 0
(-6865 2615);
PAINT ORANGE (-6865 2615);
DISPLAY INVISIBLE (-6865 2615);
FORCEADD INTEL_CORP_BPAGE..1
(-100 50);
FORCEPROP 1 LAST CDS_CON_LAST_MODIFIED Fri Jun 16 17:48:27 2017
J 0
(-1525 375);
DISPLAY 1.340426 (-1525 375);
PAINT GREEN (-1525 375);
DISPLAY INVISIBLE (-1525 375);
FORCEPROP 1 LAST CUSTOM_TXT_CDS <CURRENT_DESIGN_SHEET> OF <TOTAL_DESIGN_SHEETS>
J 0
(-600 75);
PAINT ORANGE (-600 75);
FORCEPROP 1 LAST CUSTOM_TXT_CDS <CON_LAST_MODIFIED>
J 0
(-4100 150);
PAINT ORANGE (-4100 150);
FORCEPROP 2 LAST CUSTOM_TXT_CDS <XR_PAGE_TITLE>
J 0
(-7990 5300);
DISPLAY 0.638298 (-7990 5300);
PAINT PINK (-7990 5300);
DISPLAY INVISIBLE (-7990 5300);
FORCEPROP 1 LAST SCH_TITLE SKYLAKE - SKT1 - 20 OF 21
J 0
(-8050 100);
DISPLAY 1.212766 (-8050 100);
PAINT GREEN (-8050 100);
FORCEPROP 2 LAST CDS_LIB mstr_symbols
J 0
(-100 50);
PAINT ORANGE (-100 50);
DISPLAY INVISIBLE (-100 50);
FORCEPROP 2 LAST PAGE_BORDER TRUE
J 0
(-7990 5300);
DISPLAY 0.851064 (-7990 5300);
PAINT PINK (-7990 5300);
DISPLAY INVISIBLE (-7990 5300);
FORCEPROP 1 LAST COMMENT_BODY TRUE
J 0
(-88 62);
DISPLAY 0.638298 (-88 62);
PAINT GREEN (-88 62);
DISPLAY INVISIBLE (-88 62);
FORCEPROP 2 LAST CDS_XR_PAGE_TITLE CR-74 : @BASEBOARD_FAB2_LIB.BASEBOARD_FAB2(SCH_1):PAGE74
J 0
(-7990 5300);
DISPLAY 0.638298 (-7990 5300);
PAINT PINK (-7990 5300);
DISPLAY INVISIBLE (-7990 5300);
WIRE 16 -1 (-7625 650)(-7625 525);
WIRE 16 -1 (-7625 700)(-7625 650);
WIRE 16 -1 (-7625 650)(-7475 650);
WIRE 16 -1 (-7625 750)(-7625 700);
WIRE 16 -1 (-7475 700)(-7625 700);
WIRE 16 -1 (-7625 800)(-7625 750);
WIRE 16 -1 (-7475 750)(-7625 750);
WIRE 16 -1 (-7625 850)(-7625 800);
WIRE 16 -1 (-7475 800)(-7625 800);
WIRE 16 -1 (-7625 900)(-7625 850);
WIRE 16 -1 (-7475 850)(-7625 850);
WIRE 16 -1 (-7625 950)(-7625 900);
WIRE 16 -1 (-7475 900)(-7625 900);
WIRE 16 -1 (-7625 1000)(-7625 950);
WIRE 16 -1 (-7475 950)(-7625 950);
WIRE 16 -1 (-7625 1050)(-7625 1000);
WIRE 16 -1 (-7475 1000)(-7625 1000);
WIRE 16 -1 (-7625 1100)(-7625 1050);
WIRE 16 -1 (-7475 1050)(-7625 1050);
WIRE 16 -1 (-7625 1150)(-7625 1100);
WIRE 16 -1 (-7475 1100)(-7625 1100);
WIRE 16 -1 (-7625 1200)(-7625 1150);
WIRE 16 -1 (-7475 1150)(-7625 1150);
WIRE 16 -1 (-7625 1250)(-7625 1200);
WIRE 16 -1 (-7475 1200)(-7625 1200);
WIRE 16 -1 (-7625 1300)(-7625 1250);
WIRE 16 -1 (-7475 1250)(-7625 1250);
WIRE 16 -1 (-7625 1350)(-7625 1300);
WIRE 16 -1 (-7475 1300)(-7625 1300);
WIRE 16 -1 (-7625 1400)(-7625 1350);
WIRE 16 -1 (-7475 1350)(-7625 1350);
WIRE 16 -1 (-7625 1450)(-7625 1400);
WIRE 16 -1 (-7475 1400)(-7625 1400);
WIRE 16 -1 (-7625 1500)(-7625 1450);
WIRE 16 -1 (-7475 1450)(-7625 1450);
WIRE 16 -1 (-7625 1550)(-7625 1500);
WIRE 16 -1 (-7475 1500)(-7625 1500);
WIRE 16 -1 (-7625 1600)(-7625 1550);
WIRE 16 -1 (-7475 1550)(-7625 1550);
WIRE 16 -1 (-7625 1650)(-7625 1600);
WIRE 16 -1 (-7475 1600)(-7625 1600);
WIRE 16 -1 (-7625 1700)(-7625 1650);
WIRE 16 -1 (-7475 1650)(-7625 1650);
WIRE 16 -1 (-7625 1750)(-7625 1700);
WIRE 16 -1 (-7475 1700)(-7625 1700);
WIRE 16 -1 (-7625 1800)(-7625 1750);
WIRE 16 -1 (-7475 1750)(-7625 1750);
WIRE 16 -1 (-7625 1850)(-7625 1800);
WIRE 16 -1 (-7475 1800)(-7625 1800);
WIRE 16 -1 (-7625 1900)(-7625 1850);
WIRE 16 -1 (-7475 1850)(-7625 1850);
WIRE 16 -1 (-7625 1950)(-7625 1900);
WIRE 16 -1 (-7475 1900)(-7625 1900);
WIRE 16 -1 (-7625 2000)(-7625 1950);
WIRE 16 -1 (-7475 1950)(-7625 1950);
WIRE 16 -1 (-7625 2050)(-7625 2000);
WIRE 16 -1 (-7475 2000)(-7625 2000);
WIRE 16 -1 (-7625 2100)(-7625 2050);
WIRE 16 -1 (-7475 2050)(-7625 2050);
WIRE 16 -1 (-7625 2150)(-7625 2100);
WIRE 16 -1 (-7475 2100)(-7625 2100);
WIRE 16 -1 (-7625 2200)(-7625 2150);
WIRE 16 -1 (-7475 2150)(-7625 2150);
WIRE 16 -1 (-7625 2250)(-7625 2200);
WIRE 16 -1 (-7475 2200)(-7625 2200);
WIRE 16 -1 (-7625 2300)(-7625 2250);
WIRE 16 -1 (-7475 2250)(-7625 2250);
WIRE 16 -1 (-7625 2350)(-7625 2300);
WIRE 16 -1 (-7475 2300)(-7625 2300);
WIRE 16 -1 (-7625 2400)(-7625 2350);
WIRE 16 -1 (-7475 2350)(-7625 2350);
WIRE 16 -1 (-7625 2450)(-7625 2400);
WIRE 16 -1 (-7475 2400)(-7625 2400);
WIRE 16 -1 (-7625 2500)(-7625 2450);
WIRE 16 -1 (-7475 2450)(-7625 2450);
WIRE 16 -1 (-7625 2550)(-7625 2500);
WIRE 16 -1 (-7475 2500)(-7625 2500);
WIRE 16 -1 (-7625 2600)(-7625 2550);
WIRE 16 -1 (-7475 2550)(-7625 2550);
WIRE 16 -1 (-7625 2650)(-7625 2600);
WIRE 16 -1 (-7475 2600)(-7625 2600);
WIRE 16 -1 (-7625 2700)(-7625 2650);
WIRE 16 -1 (-7475 2650)(-7625 2650);
WIRE 16 -1 (-7625 2750)(-7625 2700);
WIRE 16 -1 (-7475 2700)(-7625 2700);
WIRE 16 -1 (-7625 2800)(-7625 2750);
WIRE 16 -1 (-7475 2750)(-7625 2750);
WIRE 16 -1 (-7625 2850)(-7625 2800);
WIRE 16 -1 (-7475 2800)(-7625 2800);
WIRE 16 -1 (-7625 2900)(-7625 2850);
WIRE 16 -1 (-7475 2850)(-7625 2850);
WIRE 16 -1 (-7625 2950)(-7625 2900);
WIRE 16 -1 (-7475 2900)(-7625 2900);
WIRE 16 -1 (-7625 3000)(-7625 2950);
WIRE 16 -1 (-7475 2950)(-7625 2950);
WIRE 16 -1 (-7625 3050)(-7625 3000);
WIRE 16 -1 (-7475 3000)(-7625 3000);
WIRE 16 -1 (-7625 3100)(-7625 3050);
WIRE 16 -1 (-7475 3050)(-7625 3050);
WIRE 16 -1 (-7625 3150)(-7625 3100);
WIRE 16 -1 (-7475 3100)(-7625 3100);
WIRE 16 -1 (-7625 3200)(-7625 3150);
WIRE 16 -1 (-7475 3150)(-7625 3150);
WIRE 16 -1 (-7625 3250)(-7625 3200);
WIRE 16 -1 (-7475 3200)(-7625 3200);
WIRE 16 -1 (-7625 3300)(-7625 3250);
WIRE 16 -1 (-7475 3250)(-7625 3250);
WIRE 16 -1 (-7625 3350)(-7625 3300);
WIRE 16 -1 (-7475 3300)(-7625 3300);
WIRE 16 -1 (-7625 3400)(-7625 3350);
WIRE 16 -1 (-7475 3350)(-7625 3350);
WIRE 16 -1 (-7625 3450)(-7625 3400);
WIRE 16 -1 (-7475 3400)(-7625 3400);
WIRE 16 -1 (-7625 3500)(-7625 3450);
WIRE 16 -1 (-7475 3450)(-7625 3450);
WIRE 16 -1 (-7625 3550)(-7625 3500);
WIRE 16 -1 (-7475 3500)(-7625 3500);
WIRE 16 -1 (-7625 3600)(-7625 3550);
WIRE 16 -1 (-7475 3550)(-7625 3550);
WIRE 16 -1 (-7625 3650)(-7625 3600);
WIRE 16 -1 (-7475 3600)(-7625 3600);
WIRE 16 -1 (-7625 3700)(-7625 3650);
WIRE 16 -1 (-7475 3650)(-7625 3650);
WIRE 16 -1 (-7625 3750)(-7625 3700);
WIRE 16 -1 (-7475 3700)(-7625 3700);
WIRE 16 -1 (-7625 3800)(-7625 3750);
WIRE 16 -1 (-7475 3750)(-7625 3750);
WIRE 16 -1 (-7625 3850)(-7625 3800);
WIRE 16 -1 (-7475 3800)(-7625 3800);
WIRE 16 -1 (-7625 3900)(-7625 3850);
WIRE 16 -1 (-7475 3850)(-7625 3850);
WIRE 16 -1 (-7625 3950)(-7625 3900);
WIRE 16 -1 (-7475 3900)(-7625 3900);
WIRE 16 -1 (-7625 4000)(-7625 3950);
WIRE 16 -1 (-7475 3950)(-7625 3950);
WIRE 16 -1 (-7625 4050)(-7625 4000);
WIRE 16 -1 (-7475 4000)(-7625 4000);
WIRE 16 -1 (-7625 4100)(-7625 4050);
WIRE 16 -1 (-7475 4050)(-7625 4050);
WIRE 16 -1 (-7625 4150)(-7625 4100);
WIRE 16 -1 (-7475 4100)(-7625 4100);
WIRE 16 -1 (-7625 4200)(-7625 4150);
WIRE 16 -1 (-7475 4150)(-7625 4150);
WIRE 16 -1 (-7625 4250)(-7625 4200);
WIRE 16 -1 (-7475 4200)(-7625 4200);
WIRE 16 -1 (-7625 4300)(-7625 4250);
WIRE 16 -1 (-7475 4250)(-7625 4250);
WIRE 16 -1 (-7625 4350)(-7625 4300);
WIRE 16 -1 (-7475 4300)(-7625 4300);
WIRE 16 -1 (-7625 4400)(-7625 4350);
WIRE 16 -1 (-7475 4350)(-7625 4350);
WIRE 16 -1 (-7625 4450)(-7625 4400);
WIRE 16 -1 (-7475 4400)(-7625 4400);
WIRE 16 -1 (-7625 4500)(-7625 4450);
WIRE 16 -1 (-7475 4450)(-7625 4450);
WIRE 16 -1 (-7625 4550)(-7625 4500);
WIRE 16 -1 (-7475 4500)(-7625 4500);
WIRE 16 -1 (-7625 4600)(-7625 4550);
WIRE 16 -1 (-7475 4550)(-7625 4550);
WIRE 16 -1 (-7625 4600)(-7475 4600);
WIRE 16 -1 (-2425 675)(-2425 550);
WIRE 16 -1 (-2425 725)(-2425 675);
WIRE 16 -1 (-2600 675)(-2425 675);
WIRE 16 -1 (-2425 775)(-2425 725);
WIRE 16 -1 (-2600 725)(-2425 725);
WIRE 16 -1 (-2425 825)(-2425 775);
WIRE 16 -1 (-2600 775)(-2425 775);
WIRE 16 -1 (-2425 875)(-2425 825);
WIRE 16 -1 (-2600 825)(-2425 825);
WIRE 16 -1 (-2425 925)(-2425 875);
WIRE 16 -1 (-2600 875)(-2425 875);
WIRE 16 -1 (-2425 975)(-2425 925);
WIRE 16 -1 (-2600 925)(-2425 925);
WIRE 16 -1 (-2425 1025)(-2425 975);
WIRE 16 -1 (-2600 975)(-2425 975);
WIRE 16 -1 (-2425 1075)(-2425 1025);
WIRE 16 -1 (-2600 1025)(-2425 1025);
WIRE 16 -1 (-2425 1125)(-2425 1075);
WIRE 16 -1 (-2600 1075)(-2425 1075);
WIRE 16 -1 (-2425 1175)(-2425 1125);
WIRE 16 -1 (-2600 1125)(-2425 1125);
WIRE 16 -1 (-2425 1225)(-2425 1175);
WIRE 16 -1 (-2600 1175)(-2425 1175);
WIRE 16 -1 (-2425 1275)(-2425 1225);
WIRE 16 -1 (-2600 1225)(-2425 1225);
WIRE 16 -1 (-2425 1325)(-2425 1275);
WIRE 16 -1 (-2600 1275)(-2425 1275);
WIRE 16 -1 (-2425 1375)(-2425 1325);
WIRE 16 -1 (-2600 1325)(-2425 1325);
WIRE 16 -1 (-2425 1425)(-2425 1375);
WIRE 16 -1 (-2600 1375)(-2425 1375);
WIRE 16 -1 (-2425 1475)(-2425 1425);
WIRE 16 -1 (-2600 1425)(-2425 1425);
WIRE 16 -1 (-2425 1525)(-2425 1475);
WIRE 16 -1 (-2600 1475)(-2425 1475);
WIRE 16 -1 (-2425 1575)(-2425 1525);
WIRE 16 -1 (-2600 1525)(-2425 1525);
WIRE 16 -1 (-2425 1625)(-2425 1575);
WIRE 16 -1 (-2600 1575)(-2425 1575);
WIRE 16 -1 (-2425 1675)(-2425 1625);
WIRE 16 -1 (-2600 1625)(-2425 1625);
WIRE 16 -1 (-2425 1725)(-2425 1675);
WIRE 16 -1 (-2600 1675)(-2425 1675);
WIRE 16 -1 (-2425 1775)(-2425 1725);
WIRE 16 -1 (-2600 1725)(-2425 1725);
WIRE 16 -1 (-2425 1825)(-2425 1775);
WIRE 16 -1 (-2600 1775)(-2425 1775);
WIRE 16 -1 (-2425 1875)(-2425 1825);
WIRE 16 -1 (-2600 1825)(-2425 1825);
WIRE 16 -1 (-2425 1925)(-2425 1875);
WIRE 16 -1 (-2600 1875)(-2425 1875);
WIRE 16 -1 (-2425 1975)(-2425 1925);
WIRE 16 -1 (-2600 1925)(-2425 1925);
WIRE 16 -1 (-2425 2025)(-2425 1975);
WIRE 16 -1 (-2600 1975)(-2425 1975);
WIRE 16 -1 (-2425 2075)(-2425 2025);
WIRE 16 -1 (-2600 2025)(-2425 2025);
WIRE 16 -1 (-2425 2125)(-2425 2075);
WIRE 16 -1 (-2600 2075)(-2425 2075);
WIRE 16 -1 (-2425 2175)(-2425 2125);
WIRE 16 -1 (-2600 2125)(-2425 2125);
WIRE 16 -1 (-2425 2225)(-2425 2175);
WIRE 16 -1 (-2600 2175)(-2425 2175);
WIRE 16 -1 (-2425 2275)(-2425 2225);
WIRE 16 -1 (-2600 2225)(-2425 2225);
WIRE 16 -1 (-2425 2325)(-2425 2275);
WIRE 16 -1 (-2600 2275)(-2425 2275);
WIRE 16 -1 (-2425 2375)(-2425 2325);
WIRE 16 -1 (-2600 2325)(-2425 2325);
WIRE 16 -1 (-2425 2425)(-2425 2375);
WIRE 16 -1 (-2600 2375)(-2425 2375);
WIRE 16 -1 (-2425 2475)(-2425 2425);
WIRE 16 -1 (-2600 2425)(-2425 2425);
WIRE 16 -1 (-2425 2525)(-2425 2475);
WIRE 16 -1 (-2600 2475)(-2425 2475);
WIRE 16 -1 (-2425 2575)(-2425 2525);
WIRE 16 -1 (-2600 2525)(-2425 2525);
WIRE 16 -1 (-2425 2625)(-2425 2575);
WIRE 16 -1 (-2600 2575)(-2425 2575);
WIRE 16 -1 (-2425 2675)(-2425 2625);
WIRE 16 -1 (-2600 2625)(-2425 2625);
WIRE 16 -1 (-2425 2725)(-2425 2675);
WIRE 16 -1 (-2600 2675)(-2425 2675);
WIRE 16 -1 (-2425 2775)(-2425 2725);
WIRE 16 -1 (-2600 2725)(-2425 2725);
WIRE 16 -1 (-2425 2825)(-2425 2775);
WIRE 16 -1 (-2600 2775)(-2425 2775);
WIRE 16 -1 (-2425 2875)(-2425 2825);
WIRE 16 -1 (-2600 2825)(-2425 2825);
WIRE 16 -1 (-2425 2925)(-2425 2875);
WIRE 16 -1 (-2600 2875)(-2425 2875);
WIRE 16 -1 (-2425 2975)(-2425 2925);
WIRE 16 -1 (-2600 2925)(-2425 2925);
WIRE 16 -1 (-2425 3025)(-2425 2975);
WIRE 16 -1 (-2600 2975)(-2425 2975);
WIRE 16 -1 (-2425 3075)(-2425 3025);
WIRE 16 -1 (-2600 3025)(-2425 3025);
WIRE 16 -1 (-2425 3125)(-2425 3075);
WIRE 16 -1 (-2600 3075)(-2425 3075);
WIRE 16 -1 (-2425 3175)(-2425 3125);
WIRE 16 -1 (-2600 3125)(-2425 3125);
WIRE 16 -1 (-2425 3225)(-2425 3175);
WIRE 16 -1 (-2600 3175)(-2425 3175);
WIRE 16 -1 (-2425 3275)(-2425 3225);
WIRE 16 -1 (-2600 3225)(-2425 3225);
WIRE 16 -1 (-2425 3325)(-2425 3275);
WIRE 16 -1 (-2600 3275)(-2425 3275);
WIRE 16 -1 (-2425 3375)(-2425 3325);
WIRE 16 -1 (-2600 3325)(-2425 3325);
WIRE 16 -1 (-2425 3425)(-2425 3375);
WIRE 16 -1 (-2600 3375)(-2425 3375);
WIRE 16 -1 (-2425 3475)(-2425 3425);
WIRE 16 -1 (-2600 3425)(-2425 3425);
WIRE 16 -1 (-2425 3525)(-2425 3475);
WIRE 16 -1 (-2600 3475)(-2425 3475);
WIRE 16 -1 (-2425 3575)(-2425 3525);
WIRE 16 -1 (-2600 3525)(-2425 3525);
WIRE 16 -1 (-2425 3625)(-2425 3575);
WIRE 16 -1 (-2600 3575)(-2425 3575);
WIRE 16 -1 (-2425 3675)(-2425 3625);
WIRE 16 -1 (-2600 3625)(-2425 3625);
WIRE 16 -1 (-2425 3725)(-2425 3675);
WIRE 16 -1 (-2600 3675)(-2425 3675);
WIRE 16 -1 (-2425 3775)(-2425 3725);
WIRE 16 -1 (-2600 3725)(-2425 3725);
WIRE 16 -1 (-2425 3825)(-2425 3775);
WIRE 16 -1 (-2600 3775)(-2425 3775);
WIRE 16 -1 (-2425 3875)(-2425 3825);
WIRE 16 -1 (-2600 3825)(-2425 3825);
WIRE 16 -1 (-2425 3925)(-2425 3875);
WIRE 16 -1 (-2600 3875)(-2425 3875);
WIRE 16 -1 (-2425 3975)(-2425 3925);
WIRE 16 -1 (-2600 3925)(-2425 3925);
WIRE 16 -1 (-2425 4025)(-2425 3975);
WIRE 16 -1 (-2600 3975)(-2425 3975);
WIRE 16 -1 (-2425 4075)(-2425 4025);
WIRE 16 -1 (-2600 4025)(-2425 4025);
WIRE 16 -1 (-2425 4125)(-2425 4075);
WIRE 16 -1 (-2600 4075)(-2425 4075);
WIRE 16 -1 (-2425 4175)(-2425 4125);
WIRE 16 -1 (-2600 4125)(-2425 4125);
WIRE 16 -1 (-2425 4225)(-2425 4175);
WIRE 16 -1 (-2600 4175)(-2425 4175);
WIRE 16 -1 (-2425 4275)(-2425 4225);
WIRE 16 -1 (-2600 4225)(-2425 4225);
WIRE 16 -1 (-2425 4325)(-2425 4275);
WIRE 16 -1 (-2600 4275)(-2425 4275);
WIRE 16 -1 (-2425 4375)(-2425 4325);
WIRE 16 -1 (-2600 4325)(-2425 4325);
WIRE 16 -1 (-2425 4425)(-2425 4375);
WIRE 16 -1 (-2600 4375)(-2425 4375);
WIRE 16 -1 (-2425 4475)(-2425 4425);
WIRE 16 -1 (-2600 4425)(-2425 4425);
WIRE 16 -1 (-2425 4525)(-2425 4475);
WIRE 16 -1 (-2600 4475)(-2425 4475);
WIRE 16 -1 (-2425 4575)(-2425 4525);
WIRE 16 -1 (-2600 4525)(-2425 4525);
WIRE 16 -1 (-2425 4625)(-2425 4575);
WIRE 16 -1 (-2600 4575)(-2425 4575);
WIRE 16 -1 (-2600 4625)(-2425 4625);
WIRE 16 -1 (-2025 650)(-2025 525);
WIRE 16 -1 (-2025 700)(-2025 650);
WIRE 16 -1 (-2025 650)(-1875 650);
WIRE 16 -1 (-2025 750)(-2025 700);
WIRE 16 -1 (-1875 700)(-2025 700);
WIRE 16 -1 (-2025 800)(-2025 750);
WIRE 16 -1 (-1875 750)(-2025 750);
WIRE 16 -1 (-2025 850)(-2025 800);
WIRE 16 -1 (-1875 800)(-2025 800);
WIRE 16 -1 (-2025 900)(-2025 850);
WIRE 16 -1 (-1875 850)(-2025 850);
WIRE 16 -1 (-2025 950)(-2025 900);
WIRE 16 -1 (-1875 900)(-2025 900);
WIRE 16 -1 (-2025 1000)(-2025 950);
WIRE 16 -1 (-1875 950)(-2025 950);
WIRE 16 -1 (-2025 1050)(-2025 1000);
WIRE 16 -1 (-1875 1000)(-2025 1000);
WIRE 16 -1 (-2025 1100)(-2025 1050);
WIRE 16 -1 (-1875 1050)(-2025 1050);
WIRE 16 -1 (-2025 1150)(-2025 1100);
WIRE 16 -1 (-1875 1100)(-2025 1100);
WIRE 16 -1 (-2025 1200)(-2025 1150);
WIRE 16 -1 (-1875 1150)(-2025 1150);
WIRE 16 -1 (-2025 1250)(-2025 1200);
WIRE 16 -1 (-1875 1200)(-2025 1200);
WIRE 16 -1 (-2025 1300)(-2025 1250);
WIRE 16 -1 (-1875 1250)(-2025 1250);
WIRE 16 -1 (-2025 1350)(-2025 1300);
WIRE 16 -1 (-1875 1300)(-2025 1300);
WIRE 16 -1 (-2025 1400)(-2025 1350);
WIRE 16 -1 (-1875 1350)(-2025 1350);
WIRE 16 -1 (-2025 1450)(-2025 1400);
WIRE 16 -1 (-1875 1400)(-2025 1400);
WIRE 16 -1 (-2025 1500)(-2025 1450);
WIRE 16 -1 (-1875 1450)(-2025 1450);
WIRE 16 -1 (-2025 1550)(-2025 1500);
WIRE 16 -1 (-1875 1500)(-2025 1500);
WIRE 16 -1 (-2025 1600)(-2025 1550);
WIRE 16 -1 (-1875 1550)(-2025 1550);
WIRE 16 -1 (-2025 1650)(-2025 1600);
WIRE 16 -1 (-1875 1600)(-2025 1600);
WIRE 16 -1 (-2025 1700)(-2025 1650);
WIRE 16 -1 (-1875 1650)(-2025 1650);
WIRE 16 -1 (-2025 1750)(-2025 1700);
WIRE 16 -1 (-1875 1700)(-2025 1700);
WIRE 16 -1 (-2025 1800)(-2025 1750);
WIRE 16 -1 (-1875 1750)(-2025 1750);
WIRE 16 -1 (-2025 1850)(-2025 1800);
WIRE 16 -1 (-1875 1800)(-2025 1800);
WIRE 16 -1 (-2025 1900)(-2025 1850);
WIRE 16 -1 (-1875 1850)(-2025 1850);
WIRE 16 -1 (-2025 1950)(-2025 1900);
WIRE 16 -1 (-1875 1900)(-2025 1900);
WIRE 16 -1 (-2025 2000)(-2025 1950);
WIRE 16 -1 (-1875 1950)(-2025 1950);
WIRE 16 -1 (-2025 2050)(-2025 2000);
WIRE 16 -1 (-1875 2000)(-2025 2000);
WIRE 16 -1 (-2025 2100)(-2025 2050);
WIRE 16 -1 (-1875 2050)(-2025 2050);
WIRE 16 -1 (-2025 2150)(-2025 2100);
WIRE 16 -1 (-1875 2100)(-2025 2100);
WIRE 16 -1 (-2025 2200)(-2025 2150);
WIRE 16 -1 (-1875 2150)(-2025 2150);
WIRE 16 -1 (-2025 2250)(-2025 2200);
WIRE 16 -1 (-1875 2200)(-2025 2200);
WIRE 16 -1 (-2025 2300)(-2025 2250);
WIRE 16 -1 (-1875 2250)(-2025 2250);
WIRE 16 -1 (-2025 2350)(-2025 2300);
WIRE 16 -1 (-1875 2300)(-2025 2300);
WIRE 16 -1 (-2025 2400)(-2025 2350);
WIRE 16 -1 (-1875 2350)(-2025 2350);
WIRE 16 -1 (-2025 2450)(-2025 2400);
WIRE 16 -1 (-1875 2400)(-2025 2400);
WIRE 16 -1 (-2025 2500)(-2025 2450);
WIRE 16 -1 (-1875 2450)(-2025 2450);
WIRE 16 -1 (-2025 2550)(-2025 2500);
WIRE 16 -1 (-1875 2500)(-2025 2500);
WIRE 16 -1 (-2025 2600)(-2025 2550);
WIRE 16 -1 (-1875 2550)(-2025 2550);
WIRE 16 -1 (-2025 2650)(-2025 2600);
WIRE 16 -1 (-1875 2600)(-2025 2600);
WIRE 16 -1 (-2025 2700)(-2025 2650);
WIRE 16 -1 (-1875 2650)(-2025 2650);
WIRE 16 -1 (-2025 2750)(-2025 2700);
WIRE 16 -1 (-1875 2700)(-2025 2700);
WIRE 16 -1 (-2025 2800)(-2025 2750);
WIRE 16 -1 (-1875 2750)(-2025 2750);
WIRE 16 -1 (-2025 2850)(-2025 2800);
WIRE 16 -1 (-1875 2800)(-2025 2800);
WIRE 16 -1 (-2025 2900)(-2025 2850);
WIRE 16 -1 (-1875 2850)(-2025 2850);
WIRE 16 -1 (-2025 2950)(-2025 2900);
WIRE 16 -1 (-1875 2900)(-2025 2900);
WIRE 16 -1 (-2025 3000)(-2025 2950);
WIRE 16 -1 (-1875 2950)(-2025 2950);
WIRE 16 -1 (-2025 3050)(-2025 3000);
WIRE 16 -1 (-1875 3000)(-2025 3000);
WIRE 16 -1 (-2025 3100)(-2025 3050);
WIRE 16 -1 (-1875 3050)(-2025 3050);
WIRE 16 -1 (-2025 3150)(-2025 3100);
WIRE 16 -1 (-1875 3100)(-2025 3100);
WIRE 16 -1 (-2025 3200)(-2025 3150);
WIRE 16 -1 (-1875 3150)(-2025 3150);
WIRE 16 -1 (-2025 3250)(-2025 3200);
WIRE 16 -1 (-1875 3200)(-2025 3200);
WIRE 16 -1 (-2025 3300)(-2025 3250);
WIRE 16 -1 (-1875 3250)(-2025 3250);
WIRE 16 -1 (-2025 3350)(-2025 3300);
WIRE 16 -1 (-1875 3300)(-2025 3300);
WIRE 16 -1 (-2025 3400)(-2025 3350);
WIRE 16 -1 (-1875 3350)(-2025 3350);
WIRE 16 -1 (-2025 3450)(-2025 3400);
WIRE 16 -1 (-1875 3400)(-2025 3400);
WIRE 16 -1 (-2025 3500)(-2025 3450);
WIRE 16 -1 (-1875 3450)(-2025 3450);
WIRE 16 -1 (-2025 3550)(-2025 3500);
WIRE 16 -1 (-1875 3500)(-2025 3500);
WIRE 16 -1 (-2025 3600)(-2025 3550);
WIRE 16 -1 (-1875 3550)(-2025 3550);
WIRE 16 -1 (-2025 3650)(-2025 3600);
WIRE 16 -1 (-1875 3600)(-2025 3600);
WIRE 16 -1 (-2025 3700)(-2025 3650);
WIRE 16 -1 (-1875 3650)(-2025 3650);
WIRE 16 -1 (-2025 3750)(-2025 3700);
WIRE 16 -1 (-1875 3700)(-2025 3700);
WIRE 16 -1 (-2025 3800)(-2025 3750);
WIRE 16 -1 (-1875 3750)(-2025 3750);
WIRE 16 -1 (-2025 3850)(-2025 3800);
WIRE 16 -1 (-1875 3800)(-2025 3800);
WIRE 16 -1 (-2025 3900)(-2025 3850);
WIRE 16 -1 (-1875 3850)(-2025 3850);
WIRE 16 -1 (-2025 3950)(-2025 3900);
WIRE 16 -1 (-1875 3900)(-2025 3900);
WIRE 16 -1 (-2025 4000)(-2025 3950);
WIRE 16 -1 (-1875 3950)(-2025 3950);
WIRE 16 -1 (-2025 4050)(-2025 4000);
WIRE 16 -1 (-1875 4000)(-2025 4000);
WIRE 16 -1 (-2025 4100)(-2025 4050);
WIRE 16 -1 (-1875 4050)(-2025 4050);
WIRE 16 -1 (-2025 4150)(-2025 4100);
WIRE 16 -1 (-1875 4100)(-2025 4100);
WIRE 16 -1 (-2025 4200)(-2025 4150);
WIRE 16 -1 (-1875 4150)(-2025 4150);
WIRE 16 -1 (-2025 4250)(-2025 4200);
WIRE 16 -1 (-1875 4200)(-2025 4200);
WIRE 16 -1 (-2025 4300)(-2025 4250);
WIRE 16 -1 (-1875 4250)(-2025 4250);
WIRE 16 -1 (-2025 4350)(-2025 4300);
WIRE 16 -1 (-1875 4300)(-2025 4300);
WIRE 16 -1 (-2025 4400)(-2025 4350);
WIRE 16 -1 (-1875 4350)(-2025 4350);
WIRE 16 -1 (-2025 4450)(-2025 4400);
WIRE 16 -1 (-1875 4400)(-2025 4400);
WIRE 16 -1 (-2025 4500)(-2025 4450);
WIRE 16 -1 (-1875 4450)(-2025 4450);
WIRE 16 -1 (-2025 4550)(-2025 4500);
WIRE 16 -1 (-1875 4500)(-2025 4500);
WIRE 16 -1 (-2025 4600)(-2025 4550);
WIRE 16 -1 (-1875 4550)(-2025 4550);
WIRE 16 -1 (-2025 4600)(-1875 4600);
WIRE 16 -1 (-500 650)(-500 525);
WIRE 16 -1 (-500 700)(-500 650);
WIRE 16 -1 (-675 650)(-500 650);
WIRE 16 -1 (-500 750)(-500 700);
WIRE 16 -1 (-675 700)(-500 700);
WIRE 16 -1 (-500 800)(-500 750);
WIRE 16 -1 (-675 750)(-500 750);
WIRE 16 -1 (-500 850)(-500 800);
WIRE 16 -1 (-675 800)(-500 800);
WIRE 16 -1 (-500 900)(-500 850);
WIRE 16 -1 (-675 850)(-500 850);
WIRE 16 -1 (-500 950)(-500 900);
WIRE 16 -1 (-675 900)(-500 900);
WIRE 16 -1 (-500 1000)(-500 950);
WIRE 16 -1 (-675 950)(-500 950);
WIRE 16 -1 (-500 1050)(-500 1000);
WIRE 16 -1 (-675 1000)(-500 1000);
WIRE 16 -1 (-500 1100)(-500 1050);
WIRE 16 -1 (-675 1050)(-500 1050);
WIRE 16 -1 (-500 1150)(-500 1100);
WIRE 16 -1 (-675 1100)(-500 1100);
WIRE 16 -1 (-500 1200)(-500 1150);
WIRE 16 -1 (-675 1150)(-500 1150);
WIRE 16 -1 (-500 1250)(-500 1200);
WIRE 16 -1 (-675 1200)(-500 1200);
WIRE 16 -1 (-500 1300)(-500 1250);
WIRE 16 -1 (-675 1250)(-500 1250);
WIRE 16 -1 (-500 1350)(-500 1300);
WIRE 16 -1 (-675 1300)(-500 1300);
WIRE 16 -1 (-500 1400)(-500 1350);
WIRE 16 -1 (-675 1350)(-500 1350);
WIRE 16 -1 (-500 1450)(-500 1400);
WIRE 16 -1 (-675 1400)(-500 1400);
WIRE 16 -1 (-500 1500)(-500 1450);
WIRE 16 -1 (-675 1450)(-500 1450);
WIRE 16 -1 (-500 1550)(-500 1500);
WIRE 16 -1 (-675 1500)(-500 1500);
WIRE 16 -1 (-500 1600)(-500 1550);
WIRE 16 -1 (-675 1550)(-500 1550);
WIRE 16 -1 (-500 1650)(-500 1600);
WIRE 16 -1 (-675 1600)(-500 1600);
WIRE 16 -1 (-500 1700)(-500 1650);
WIRE 16 -1 (-675 1650)(-500 1650);
WIRE 16 -1 (-500 1750)(-500 1700);
WIRE 16 -1 (-675 1700)(-500 1700);
WIRE 16 -1 (-500 1800)(-500 1750);
WIRE 16 -1 (-675 1750)(-500 1750);
WIRE 16 -1 (-500 1850)(-500 1800);
WIRE 16 -1 (-675 1800)(-500 1800);
WIRE 16 -1 (-500 1900)(-500 1850);
WIRE 16 -1 (-675 1850)(-500 1850);
WIRE 16 -1 (-500 1950)(-500 1900);
WIRE 16 -1 (-675 1900)(-500 1900);
WIRE 16 -1 (-500 2000)(-500 1950);
WIRE 16 -1 (-675 1950)(-500 1950);
WIRE 16 -1 (-500 2050)(-500 2000);
WIRE 16 -1 (-675 2000)(-500 2000);
WIRE 16 -1 (-500 2100)(-500 2050);
WIRE 16 -1 (-675 2050)(-500 2050);
WIRE 16 -1 (-500 2150)(-500 2100);
WIRE 16 -1 (-675 2100)(-500 2100);
WIRE 16 -1 (-500 2200)(-500 2150);
WIRE 16 -1 (-675 2150)(-500 2150);
WIRE 16 -1 (-500 2250)(-500 2200);
WIRE 16 -1 (-675 2200)(-500 2200);
WIRE 16 -1 (-500 2300)(-500 2250);
WIRE 16 -1 (-675 2250)(-500 2250);
WIRE 16 -1 (-500 2350)(-500 2300);
WIRE 16 -1 (-675 2300)(-500 2300);
WIRE 16 -1 (-500 2400)(-500 2350);
WIRE 16 -1 (-675 2350)(-500 2350);
WIRE 16 -1 (-500 2450)(-500 2400);
WIRE 16 -1 (-675 2400)(-500 2400);
WIRE 16 -1 (-500 2500)(-500 2450);
WIRE 16 -1 (-675 2450)(-500 2450);
WIRE 16 -1 (-500 2550)(-500 2500);
WIRE 16 -1 (-675 2500)(-500 2500);
WIRE 16 -1 (-500 2600)(-500 2550);
WIRE 16 -1 (-675 2550)(-500 2550);
WIRE 16 -1 (-500 2650)(-500 2600);
WIRE 16 -1 (-675 2600)(-500 2600);
WIRE 16 -1 (-500 2700)(-500 2650);
WIRE 16 -1 (-675 2650)(-500 2650);
WIRE 16 -1 (-500 2750)(-500 2700);
WIRE 16 -1 (-675 2700)(-500 2700);
WIRE 16 -1 (-500 2800)(-500 2750);
WIRE 16 -1 (-675 2750)(-500 2750);
WIRE 16 -1 (-500 2850)(-500 2800);
WIRE 16 -1 (-675 2800)(-500 2800);
WIRE 16 -1 (-500 2900)(-500 2850);
WIRE 16 -1 (-675 2850)(-500 2850);
WIRE 16 -1 (-500 2950)(-500 2900);
WIRE 16 -1 (-675 2900)(-500 2900);
WIRE 16 -1 (-500 3000)(-500 2950);
WIRE 16 -1 (-675 2950)(-500 2950);
WIRE 16 -1 (-500 3050)(-500 3000);
WIRE 16 -1 (-675 3000)(-500 3000);
WIRE 16 -1 (-500 3100)(-500 3050);
WIRE 16 -1 (-675 3050)(-500 3050);
WIRE 16 -1 (-500 3150)(-500 3100);
WIRE 16 -1 (-675 3100)(-500 3100);
WIRE 16 -1 (-500 3200)(-500 3150);
WIRE 16 -1 (-675 3150)(-500 3150);
WIRE 16 -1 (-500 3250)(-500 3200);
WIRE 16 -1 (-675 3200)(-500 3200);
WIRE 16 -1 (-500 3300)(-500 3250);
WIRE 16 -1 (-675 3250)(-500 3250);
WIRE 16 -1 (-500 3350)(-500 3300);
WIRE 16 -1 (-675 3300)(-500 3300);
WIRE 16 -1 (-500 3400)(-500 3350);
WIRE 16 -1 (-675 3350)(-500 3350);
WIRE 16 -1 (-500 3450)(-500 3400);
WIRE 16 -1 (-675 3400)(-500 3400);
WIRE 16 -1 (-500 3500)(-500 3450);
WIRE 16 -1 (-675 3450)(-500 3450);
WIRE 16 -1 (-500 3550)(-500 3500);
WIRE 16 -1 (-675 3500)(-500 3500);
WIRE 16 -1 (-500 3600)(-500 3550);
WIRE 16 -1 (-675 3550)(-500 3550);
WIRE 16 -1 (-500 3650)(-500 3600);
WIRE 16 -1 (-675 3600)(-500 3600);
WIRE 16 -1 (-500 3700)(-500 3650);
WIRE 16 -1 (-675 3650)(-500 3650);
WIRE 16 -1 (-500 3750)(-500 3700);
WIRE 16 -1 (-675 3700)(-500 3700);
WIRE 16 -1 (-500 3800)(-500 3750);
WIRE 16 -1 (-675 3750)(-500 3750);
WIRE 16 -1 (-500 3850)(-500 3800);
WIRE 16 -1 (-675 3800)(-500 3800);
WIRE 16 -1 (-500 3900)(-500 3850);
WIRE 16 -1 (-675 3850)(-500 3850);
WIRE 16 -1 (-500 3950)(-500 3900);
WIRE 16 -1 (-675 3900)(-500 3900);
WIRE 16 -1 (-500 4000)(-500 3950);
WIRE 16 -1 (-675 3950)(-500 3950);
WIRE 16 -1 (-500 4050)(-500 4000);
WIRE 16 -1 (-675 4000)(-500 4000);
WIRE 16 -1 (-500 4100)(-500 4050);
WIRE 16 -1 (-675 4050)(-500 4050);
WIRE 16 -1 (-500 4150)(-500 4100);
WIRE 16 -1 (-675 4100)(-500 4100);
WIRE 16 -1 (-500 4200)(-500 4150);
WIRE 16 -1 (-675 4150)(-500 4150);
WIRE 16 -1 (-500 4250)(-500 4200);
WIRE 16 -1 (-675 4200)(-500 4200);
WIRE 16 -1 (-500 4300)(-500 4250);
WIRE 16 -1 (-675 4250)(-500 4250);
WIRE 16 -1 (-500 4350)(-500 4300);
WIRE 16 -1 (-675 4300)(-500 4300);
WIRE 16 -1 (-500 4400)(-500 4350);
WIRE 16 -1 (-675 4350)(-500 4350);
WIRE 16 -1 (-500 4450)(-500 4400);
WIRE 16 -1 (-675 4400)(-500 4400);
WIRE 16 -1 (-500 4500)(-500 4450);
WIRE 16 -1 (-675 4450)(-500 4450);
WIRE 16 -1 (-500 4550)(-500 4500);
WIRE 16 -1 (-675 4500)(-500 4500);
WIRE 16 -1 (-500 4600)(-500 4550);
WIRE 16 -1 (-675 4550)(-500 4550);
WIRE 16 -1 (-675 4600)(-500 4600);
WIRE 16 -1 (-6100 650)(-6100 525);
WIRE 16 -1 (-6100 700)(-6100 650);
WIRE 16 -1 (-6275 650)(-6100 650);
WIRE 16 -1 (-6100 750)(-6100 700);
WIRE 16 -1 (-6275 700)(-6100 700);
WIRE 16 -1 (-6100 800)(-6100 750);
WIRE 16 -1 (-6275 750)(-6100 750);
WIRE 16 -1 (-6100 850)(-6100 800);
WIRE 16 -1 (-6275 800)(-6100 800);
WIRE 16 -1 (-6100 900)(-6100 850);
WIRE 16 -1 (-6275 850)(-6100 850);
WIRE 16 -1 (-6100 950)(-6100 900);
WIRE 16 -1 (-6275 900)(-6100 900);
WIRE 16 -1 (-6100 1000)(-6100 950);
WIRE 16 -1 (-6275 950)(-6100 950);
WIRE 16 -1 (-6100 1050)(-6100 1000);
WIRE 16 -1 (-6275 1000)(-6100 1000);
WIRE 16 -1 (-6100 1100)(-6100 1050);
WIRE 16 -1 (-6275 1050)(-6100 1050);
WIRE 16 -1 (-6100 1150)(-6100 1100);
WIRE 16 -1 (-6275 1100)(-6100 1100);
WIRE 16 -1 (-6100 1200)(-6100 1150);
WIRE 16 -1 (-6275 1150)(-6100 1150);
WIRE 16 -1 (-6100 1250)(-6100 1200);
WIRE 16 -1 (-6275 1200)(-6100 1200);
WIRE 16 -1 (-6100 1300)(-6100 1250);
WIRE 16 -1 (-6275 1250)(-6100 1250);
WIRE 16 -1 (-6100 1350)(-6100 1300);
WIRE 16 -1 (-6275 1300)(-6100 1300);
WIRE 16 -1 (-6100 1400)(-6100 1350);
WIRE 16 -1 (-6275 1350)(-6100 1350);
WIRE 16 -1 (-6100 1450)(-6100 1400);
WIRE 16 -1 (-6275 1400)(-6100 1400);
WIRE 16 -1 (-6100 1500)(-6100 1450);
WIRE 16 -1 (-6275 1450)(-6100 1450);
WIRE 16 -1 (-6100 1550)(-6100 1500);
WIRE 16 -1 (-6275 1500)(-6100 1500);
WIRE 16 -1 (-6100 1600)(-6100 1550);
WIRE 16 -1 (-6275 1550)(-6100 1550);
WIRE 16 -1 (-6100 1650)(-6100 1600);
WIRE 16 -1 (-6275 1600)(-6100 1600);
WIRE 16 -1 (-6100 1700)(-6100 1650);
WIRE 16 -1 (-6275 1650)(-6100 1650);
WIRE 16 -1 (-6100 1750)(-6100 1700);
WIRE 16 -1 (-6275 1700)(-6100 1700);
WIRE 16 -1 (-6100 1800)(-6100 1750);
WIRE 16 -1 (-6275 1750)(-6100 1750);
WIRE 16 -1 (-6100 1850)(-6100 1800);
WIRE 16 -1 (-6275 1800)(-6100 1800);
WIRE 16 -1 (-6100 1900)(-6100 1850);
WIRE 16 -1 (-6275 1850)(-6100 1850);
WIRE 16 -1 (-6100 1950)(-6100 1900);
WIRE 16 -1 (-6275 1900)(-6100 1900);
WIRE 16 -1 (-6100 2000)(-6100 1950);
WIRE 16 -1 (-6275 1950)(-6100 1950);
WIRE 16 -1 (-6100 2050)(-6100 2000);
WIRE 16 -1 (-6275 2000)(-6100 2000);
WIRE 16 -1 (-6100 2100)(-6100 2050);
WIRE 16 -1 (-6275 2050)(-6100 2050);
WIRE 16 -1 (-6100 2150)(-6100 2100);
WIRE 16 -1 (-6275 2100)(-6100 2100);
WIRE 16 -1 (-6100 2200)(-6100 2150);
WIRE 16 -1 (-6275 2150)(-6100 2150);
WIRE 16 -1 (-6100 2250)(-6100 2200);
WIRE 16 -1 (-6275 2200)(-6100 2200);
WIRE 16 -1 (-6100 2300)(-6100 2250);
WIRE 16 -1 (-6275 2250)(-6100 2250);
WIRE 16 -1 (-6100 2350)(-6100 2300);
WIRE 16 -1 (-6275 2300)(-6100 2300);
WIRE 16 -1 (-6100 2400)(-6100 2350);
WIRE 16 -1 (-6275 2350)(-6100 2350);
WIRE 16 -1 (-6100 2450)(-6100 2400);
WIRE 16 -1 (-6275 2400)(-6100 2400);
WIRE 16 -1 (-6100 2500)(-6100 2450);
WIRE 16 -1 (-6275 2450)(-6100 2450);
WIRE 16 -1 (-6100 2550)(-6100 2500);
WIRE 16 -1 (-6275 2500)(-6100 2500);
WIRE 16 -1 (-6100 2600)(-6100 2550);
WIRE 16 -1 (-6275 2550)(-6100 2550);
WIRE 16 -1 (-6100 2650)(-6100 2600);
WIRE 16 -1 (-6275 2600)(-6100 2600);
WIRE 16 -1 (-6100 2700)(-6100 2650);
WIRE 16 -1 (-6275 2650)(-6100 2650);
WIRE 16 -1 (-6100 2750)(-6100 2700);
WIRE 16 -1 (-6275 2700)(-6100 2700);
WIRE 16 -1 (-6100 2800)(-6100 2750);
WIRE 16 -1 (-6275 2750)(-6100 2750);
WIRE 16 -1 (-6100 2850)(-6100 2800);
WIRE 16 -1 (-6275 2800)(-6100 2800);
WIRE 16 -1 (-6100 2900)(-6100 2850);
WIRE 16 -1 (-6275 2850)(-6100 2850);
WIRE 16 -1 (-6100 2950)(-6100 2900);
WIRE 16 -1 (-6275 2900)(-6100 2900);
WIRE 16 -1 (-6100 3000)(-6100 2950);
WIRE 16 -1 (-6275 2950)(-6100 2950);
WIRE 16 -1 (-6100 3050)(-6100 3000);
WIRE 16 -1 (-6275 3000)(-6100 3000);
WIRE 16 -1 (-6100 3100)(-6100 3050);
WIRE 16 -1 (-6275 3050)(-6100 3050);
WIRE 16 -1 (-6100 3150)(-6100 3100);
WIRE 16 -1 (-6275 3100)(-6100 3100);
WIRE 16 -1 (-6100 3200)(-6100 3150);
WIRE 16 -1 (-6275 3150)(-6100 3150);
WIRE 16 -1 (-6100 3250)(-6100 3200);
WIRE 16 -1 (-6275 3200)(-6100 3200);
WIRE 16 -1 (-6100 3300)(-6100 3250);
WIRE 16 -1 (-6275 3250)(-6100 3250);
WIRE 16 -1 (-6100 3350)(-6100 3300);
WIRE 16 -1 (-6275 3300)(-6100 3300);
WIRE 16 -1 (-6100 3400)(-6100 3350);
WIRE 16 -1 (-6275 3350)(-6100 3350);
WIRE 16 -1 (-6100 3450)(-6100 3400);
WIRE 16 -1 (-6275 3400)(-6100 3400);
WIRE 16 -1 (-6100 3500)(-6100 3450);
WIRE 16 -1 (-6275 3450)(-6100 3450);
WIRE 16 -1 (-6100 3550)(-6100 3500);
WIRE 16 -1 (-6275 3500)(-6100 3500);
WIRE 16 -1 (-6100 3600)(-6100 3550);
WIRE 16 -1 (-6275 3550)(-6100 3550);
WIRE 16 -1 (-6100 3650)(-6100 3600);
WIRE 16 -1 (-6275 3600)(-6100 3600);
WIRE 16 -1 (-6100 3700)(-6100 3650);
WIRE 16 -1 (-6275 3650)(-6100 3650);
WIRE 16 -1 (-6100 3750)(-6100 3700);
WIRE 16 -1 (-6275 3700)(-6100 3700);
WIRE 16 -1 (-6100 3800)(-6100 3750);
WIRE 16 -1 (-6275 3750)(-6100 3750);
WIRE 16 -1 (-6100 3850)(-6100 3800);
WIRE 16 -1 (-6275 3800)(-6100 3800);
WIRE 16 -1 (-6100 3900)(-6100 3850);
WIRE 16 -1 (-6275 3850)(-6100 3850);
WIRE 16 -1 (-6100 3950)(-6100 3900);
WIRE 16 -1 (-6275 3900)(-6100 3900);
WIRE 16 -1 (-6100 4000)(-6100 3950);
WIRE 16 -1 (-6275 3950)(-6100 3950);
WIRE 16 -1 (-6100 4050)(-6100 4000);
WIRE 16 -1 (-6275 4000)(-6100 4000);
WIRE 16 -1 (-6100 4100)(-6100 4050);
WIRE 16 -1 (-6275 4050)(-6100 4050);
WIRE 16 -1 (-6100 4150)(-6100 4100);
WIRE 16 -1 (-6275 4100)(-6100 4100);
WIRE 16 -1 (-6100 4200)(-6100 4150);
WIRE 16 -1 (-6275 4150)(-6100 4150);
WIRE 16 -1 (-6100 4250)(-6100 4200);
WIRE 16 -1 (-6275 4200)(-6100 4200);
WIRE 16 -1 (-6100 4300)(-6100 4250);
WIRE 16 -1 (-6275 4250)(-6100 4250);
WIRE 16 -1 (-6100 4350)(-6100 4300);
WIRE 16 -1 (-6275 4300)(-6100 4300);
WIRE 16 -1 (-6100 4400)(-6100 4350);
WIRE 16 -1 (-6275 4350)(-6100 4350);
WIRE 16 -1 (-6100 4450)(-6100 4400);
WIRE 16 -1 (-6275 4400)(-6100 4400);
WIRE 16 -1 (-6100 4500)(-6100 4450);
WIRE 16 -1 (-6275 4450)(-6100 4450);
WIRE 16 -1 (-6100 4550)(-6100 4500);
WIRE 16 -1 (-6275 4500)(-6100 4500);
WIRE 16 -1 (-6100 4600)(-6100 4550);
WIRE 16 -1 (-6275 4550)(-6100 4550);
WIRE 16 -1 (-6275 4600)(-6100 4600);
WIRE 16 -1 (-5775 675)(-5775 550);
WIRE 16 -1 (-5775 725)(-5775 675);
WIRE 16 -1 (-5775 675)(-5625 675);
WIRE 16 -1 (-5775 775)(-5775 725);
WIRE 16 -1 (-5625 725)(-5775 725);
WIRE 16 -1 (-5775 825)(-5775 775);
WIRE 16 -1 (-5625 775)(-5775 775);
WIRE 16 -1 (-5775 875)(-5775 825);
WIRE 16 -1 (-5625 825)(-5775 825);
WIRE 16 -1 (-5775 925)(-5775 875);
WIRE 16 -1 (-5625 875)(-5775 875);
WIRE 16 -1 (-5775 975)(-5775 925);
WIRE 16 -1 (-5625 925)(-5775 925);
WIRE 16 -1 (-5775 1025)(-5775 975);
WIRE 16 -1 (-5625 975)(-5775 975);
WIRE 16 -1 (-5775 1075)(-5775 1025);
WIRE 16 -1 (-5625 1025)(-5775 1025);
WIRE 16 -1 (-5775 1125)(-5775 1075);
WIRE 16 -1 (-5625 1075)(-5775 1075);
WIRE 16 -1 (-5775 1175)(-5775 1125);
WIRE 16 -1 (-5625 1125)(-5775 1125);
WIRE 16 -1 (-5775 1225)(-5775 1175);
WIRE 16 -1 (-5625 1175)(-5775 1175);
WIRE 16 -1 (-5775 1275)(-5775 1225);
WIRE 16 -1 (-5625 1225)(-5775 1225);
WIRE 16 -1 (-5775 1325)(-5775 1275);
WIRE 16 -1 (-5625 1275)(-5775 1275);
WIRE 16 -1 (-5775 1375)(-5775 1325);
WIRE 16 -1 (-5625 1325)(-5775 1325);
WIRE 16 -1 (-5775 1425)(-5775 1375);
WIRE 16 -1 (-5625 1375)(-5775 1375);
WIRE 16 -1 (-5775 1475)(-5775 1425);
WIRE 16 -1 (-5625 1425)(-5775 1425);
WIRE 16 -1 (-5775 1525)(-5775 1475);
WIRE 16 -1 (-5625 1475)(-5775 1475);
WIRE 16 -1 (-5775 1575)(-5775 1525);
WIRE 16 -1 (-5625 1525)(-5775 1525);
WIRE 16 -1 (-5775 1625)(-5775 1575);
WIRE 16 -1 (-5625 1575)(-5775 1575);
WIRE 16 -1 (-5775 1675)(-5775 1625);
WIRE 16 -1 (-5625 1625)(-5775 1625);
WIRE 16 -1 (-5775 1725)(-5775 1675);
WIRE 16 -1 (-5625 1675)(-5775 1675);
WIRE 16 -1 (-5775 1775)(-5775 1725);
WIRE 16 -1 (-5625 1725)(-5775 1725);
WIRE 16 -1 (-5775 1825)(-5775 1775);
WIRE 16 -1 (-5625 1775)(-5775 1775);
WIRE 16 -1 (-5775 1875)(-5775 1825);
WIRE 16 -1 (-5625 1825)(-5775 1825);
WIRE 16 -1 (-5775 1925)(-5775 1875);
WIRE 16 -1 (-5625 1875)(-5775 1875);
WIRE 16 -1 (-5775 1975)(-5775 1925);
WIRE 16 -1 (-5625 1925)(-5775 1925);
WIRE 16 -1 (-5775 2025)(-5775 1975);
WIRE 16 -1 (-5625 1975)(-5775 1975);
WIRE 16 -1 (-5775 2075)(-5775 2025);
WIRE 16 -1 (-5625 2025)(-5775 2025);
WIRE 16 -1 (-5775 2125)(-5775 2075);
WIRE 16 -1 (-5625 2075)(-5775 2075);
WIRE 16 -1 (-5775 2175)(-5775 2125);
WIRE 16 -1 (-5625 2125)(-5775 2125);
WIRE 16 -1 (-5775 2225)(-5775 2175);
WIRE 16 -1 (-5625 2175)(-5775 2175);
WIRE 16 -1 (-5775 2275)(-5775 2225);
WIRE 16 -1 (-5625 2225)(-5775 2225);
WIRE 16 -1 (-5775 2325)(-5775 2275);
WIRE 16 -1 (-5625 2275)(-5775 2275);
WIRE 16 -1 (-5775 2375)(-5775 2325);
WIRE 16 -1 (-5625 2325)(-5775 2325);
WIRE 16 -1 (-5775 2425)(-5775 2375);
WIRE 16 -1 (-5625 2375)(-5775 2375);
WIRE 16 -1 (-5775 2475)(-5775 2425);
WIRE 16 -1 (-5625 2425)(-5775 2425);
WIRE 16 -1 (-5775 2525)(-5775 2475);
WIRE 16 -1 (-5625 2475)(-5775 2475);
WIRE 16 -1 (-5775 2575)(-5775 2525);
WIRE 16 -1 (-5625 2525)(-5775 2525);
WIRE 16 -1 (-5775 2625)(-5775 2575);
WIRE 16 -1 (-5625 2575)(-5775 2575);
WIRE 16 -1 (-5775 2675)(-5775 2625);
WIRE 16 -1 (-5625 2625)(-5775 2625);
WIRE 16 -1 (-5775 2725)(-5775 2675);
WIRE 16 -1 (-5625 2675)(-5775 2675);
WIRE 16 -1 (-5775 2775)(-5775 2725);
WIRE 16 -1 (-5625 2725)(-5775 2725);
WIRE 16 -1 (-5775 2825)(-5775 2775);
WIRE 16 -1 (-5625 2775)(-5775 2775);
WIRE 16 -1 (-5775 2875)(-5775 2825);
WIRE 16 -1 (-5625 2825)(-5775 2825);
WIRE 16 -1 (-5775 2925)(-5775 2875);
WIRE 16 -1 (-5625 2875)(-5775 2875);
WIRE 16 -1 (-5775 2975)(-5775 2925);
WIRE 16 -1 (-5625 2925)(-5775 2925);
WIRE 16 -1 (-5775 3025)(-5775 2975);
WIRE 16 -1 (-5625 2975)(-5775 2975);
WIRE 16 -1 (-5775 3075)(-5775 3025);
WIRE 16 -1 (-5625 3025)(-5775 3025);
WIRE 16 -1 (-5775 3125)(-5775 3075);
WIRE 16 -1 (-5625 3075)(-5775 3075);
WIRE 16 -1 (-5775 3175)(-5775 3125);
WIRE 16 -1 (-5625 3125)(-5775 3125);
WIRE 16 -1 (-5775 3225)(-5775 3175);
WIRE 16 -1 (-5625 3175)(-5775 3175);
WIRE 16 -1 (-5775 3275)(-5775 3225);
WIRE 16 -1 (-5625 3225)(-5775 3225);
WIRE 16 -1 (-5775 3325)(-5775 3275);
WIRE 16 -1 (-5625 3275)(-5775 3275);
WIRE 16 -1 (-5775 3375)(-5775 3325);
WIRE 16 -1 (-5625 3325)(-5775 3325);
WIRE 16 -1 (-5775 3425)(-5775 3375);
WIRE 16 -1 (-5625 3375)(-5775 3375);
WIRE 16 -1 (-5775 3475)(-5775 3425);
WIRE 16 -1 (-5625 3425)(-5775 3425);
WIRE 16 -1 (-5775 3525)(-5775 3475);
WIRE 16 -1 (-5625 3475)(-5775 3475);
WIRE 16 -1 (-5775 3575)(-5775 3525);
WIRE 16 -1 (-5625 3525)(-5775 3525);
WIRE 16 -1 (-5775 3625)(-5775 3575);
WIRE 16 -1 (-5625 3575)(-5775 3575);
WIRE 16 -1 (-5775 3675)(-5775 3625);
WIRE 16 -1 (-5625 3625)(-5775 3625);
WIRE 16 -1 (-5775 3725)(-5775 3675);
WIRE 16 -1 (-5625 3675)(-5775 3675);
WIRE 16 -1 (-5775 3775)(-5775 3725);
WIRE 16 -1 (-5625 3725)(-5775 3725);
WIRE 16 -1 (-5775 3825)(-5775 3775);
WIRE 16 -1 (-5625 3775)(-5775 3775);
WIRE 16 -1 (-5775 3875)(-5775 3825);
WIRE 16 -1 (-5625 3825)(-5775 3825);
WIRE 16 -1 (-5775 3925)(-5775 3875);
WIRE 16 -1 (-5625 3875)(-5775 3875);
WIRE 16 -1 (-5775 3975)(-5775 3925);
WIRE 16 -1 (-5625 3925)(-5775 3925);
WIRE 16 -1 (-5775 4025)(-5775 3975);
WIRE 16 -1 (-5625 3975)(-5775 3975);
WIRE 16 -1 (-5775 4075)(-5775 4025);
WIRE 16 -1 (-5625 4025)(-5775 4025);
WIRE 16 -1 (-5775 4125)(-5775 4075);
WIRE 16 -1 (-5625 4075)(-5775 4075);
WIRE 16 -1 (-5775 4175)(-5775 4125);
WIRE 16 -1 (-5625 4125)(-5775 4125);
WIRE 16 -1 (-5775 4225)(-5775 4175);
WIRE 16 -1 (-5625 4175)(-5775 4175);
WIRE 16 -1 (-5775 4275)(-5775 4225);
WIRE 16 -1 (-5625 4225)(-5775 4225);
WIRE 16 -1 (-5775 4325)(-5775 4275);
WIRE 16 -1 (-5625 4275)(-5775 4275);
WIRE 16 -1 (-5775 4375)(-5775 4325);
WIRE 16 -1 (-5625 4325)(-5775 4325);
WIRE 16 -1 (-5775 4425)(-5775 4375);
WIRE 16 -1 (-5625 4375)(-5775 4375);
WIRE 16 -1 (-5775 4475)(-5775 4425);
WIRE 16 -1 (-5625 4425)(-5775 4425);
WIRE 16 -1 (-5775 4525)(-5775 4475);
WIRE 16 -1 (-5625 4475)(-5775 4475);
WIRE 16 -1 (-5775 4575)(-5775 4525);
WIRE 16 -1 (-5625 4525)(-5775 4525);
WIRE 16 -1 (-5775 4575)(-5775 4625);
WIRE 16 -1 (-5625 4575)(-5775 4575);
WIRE 16 -1 (-5775 4625)(-5625 4625);
WIRE 16 -1 (-4250 675)(-4250 550);
WIRE 16 -1 (-4250 725)(-4250 675);
WIRE 16 -1 (-4425 675)(-4250 675);
WIRE 16 -1 (-4250 775)(-4250 725);
WIRE 16 -1 (-4425 725)(-4250 725);
WIRE 16 -1 (-4250 825)(-4250 775);
WIRE 16 -1 (-4425 775)(-4250 775);
WIRE 16 -1 (-4250 875)(-4250 825);
WIRE 16 -1 (-4425 825)(-4250 825);
WIRE 16 -1 (-4250 925)(-4250 875);
WIRE 16 -1 (-4425 875)(-4250 875);
WIRE 16 -1 (-4250 975)(-4250 925);
WIRE 16 -1 (-4425 925)(-4250 925);
WIRE 16 -1 (-4250 1025)(-4250 975);
WIRE 16 -1 (-4425 975)(-4250 975);
WIRE 16 -1 (-4250 1075)(-4250 1025);
WIRE 16 -1 (-4425 1025)(-4250 1025);
WIRE 16 -1 (-4250 1125)(-4250 1075);
WIRE 16 -1 (-4425 1075)(-4250 1075);
WIRE 16 -1 (-4250 1175)(-4250 1125);
WIRE 16 -1 (-4425 1125)(-4250 1125);
WIRE 16 -1 (-4250 1225)(-4250 1175);
WIRE 16 -1 (-4425 1175)(-4250 1175);
WIRE 16 -1 (-4250 1275)(-4250 1225);
WIRE 16 -1 (-4425 1225)(-4250 1225);
WIRE 16 -1 (-4250 1325)(-4250 1275);
WIRE 16 -1 (-4425 1275)(-4250 1275);
WIRE 16 -1 (-4250 1375)(-4250 1325);
WIRE 16 -1 (-4425 1325)(-4250 1325);
WIRE 16 -1 (-4250 1425)(-4250 1375);
WIRE 16 -1 (-4425 1375)(-4250 1375);
WIRE 16 -1 (-4250 1475)(-4250 1425);
WIRE 16 -1 (-4425 1425)(-4250 1425);
WIRE 16 -1 (-4250 1525)(-4250 1475);
WIRE 16 -1 (-4425 1475)(-4250 1475);
WIRE 16 -1 (-4250 1575)(-4250 1525);
WIRE 16 -1 (-4425 1525)(-4250 1525);
WIRE 16 -1 (-4250 1625)(-4250 1575);
WIRE 16 -1 (-4425 1575)(-4250 1575);
WIRE 16 -1 (-4250 1675)(-4250 1625);
WIRE 16 -1 (-4425 1625)(-4250 1625);
WIRE 16 -1 (-4250 1725)(-4250 1675);
WIRE 16 -1 (-4425 1675)(-4250 1675);
WIRE 16 -1 (-4250 1775)(-4250 1725);
WIRE 16 -1 (-4425 1725)(-4250 1725);
WIRE 16 -1 (-4250 1825)(-4250 1775);
WIRE 16 -1 (-4425 1775)(-4250 1775);
WIRE 16 -1 (-4250 1875)(-4250 1825);
WIRE 16 -1 (-4425 1825)(-4250 1825);
WIRE 16 -1 (-4250 1925)(-4250 1875);
WIRE 16 -1 (-4425 1875)(-4250 1875);
WIRE 16 -1 (-4250 1975)(-4250 1925);
WIRE 16 -1 (-4425 1925)(-4250 1925);
WIRE 16 -1 (-4250 2025)(-4250 1975);
WIRE 16 -1 (-4425 1975)(-4250 1975);
WIRE 16 -1 (-4250 2075)(-4250 2025);
WIRE 16 -1 (-4425 2025)(-4250 2025);
WIRE 16 -1 (-4250 2125)(-4250 2075);
WIRE 16 -1 (-4425 2075)(-4250 2075);
WIRE 16 -1 (-4250 2175)(-4250 2125);
WIRE 16 -1 (-4425 2125)(-4250 2125);
WIRE 16 -1 (-4250 2225)(-4250 2175);
WIRE 16 -1 (-4425 2175)(-4250 2175);
WIRE 16 -1 (-4250 2275)(-4250 2225);
WIRE 16 -1 (-4425 2225)(-4250 2225);
WIRE 16 -1 (-4250 2325)(-4250 2275);
WIRE 16 -1 (-4425 2275)(-4250 2275);
WIRE 16 -1 (-4250 2375)(-4250 2325);
WIRE 16 -1 (-4425 2325)(-4250 2325);
WIRE 16 -1 (-4250 2425)(-4250 2375);
WIRE 16 -1 (-4425 2375)(-4250 2375);
WIRE 16 -1 (-4250 2475)(-4250 2425);
WIRE 16 -1 (-4425 2425)(-4250 2425);
WIRE 16 -1 (-4250 2525)(-4250 2475);
WIRE 16 -1 (-4425 2475)(-4250 2475);
WIRE 16 -1 (-4250 2575)(-4250 2525);
WIRE 16 -1 (-4425 2525)(-4250 2525);
WIRE 16 -1 (-4250 2625)(-4250 2575);
WIRE 16 -1 (-4425 2575)(-4250 2575);
WIRE 16 -1 (-4250 2675)(-4250 2625);
WIRE 16 -1 (-4425 2625)(-4250 2625);
WIRE 16 -1 (-4250 2725)(-4250 2675);
WIRE 16 -1 (-4425 2675)(-4250 2675);
WIRE 16 -1 (-4250 2775)(-4250 2725);
WIRE 16 -1 (-4425 2725)(-4250 2725);
WIRE 16 -1 (-4250 2825)(-4250 2775);
WIRE 16 -1 (-4425 2775)(-4250 2775);
WIRE 16 -1 (-4250 2875)(-4250 2825);
WIRE 16 -1 (-4425 2825)(-4250 2825);
WIRE 16 -1 (-4250 2925)(-4250 2875);
WIRE 16 -1 (-4425 2875)(-4250 2875);
WIRE 16 -1 (-4250 2975)(-4250 2925);
WIRE 16 -1 (-4425 2925)(-4250 2925);
WIRE 16 -1 (-4250 3025)(-4250 2975);
WIRE 16 -1 (-4425 2975)(-4250 2975);
WIRE 16 -1 (-4250 3075)(-4250 3025);
WIRE 16 -1 (-4425 3025)(-4250 3025);
WIRE 16 -1 (-4250 3125)(-4250 3075);
WIRE 16 -1 (-4425 3075)(-4250 3075);
WIRE 16 -1 (-4250 3175)(-4250 3125);
WIRE 16 -1 (-4425 3125)(-4250 3125);
WIRE 16 -1 (-4250 3225)(-4250 3175);
WIRE 16 -1 (-4425 3175)(-4250 3175);
WIRE 16 -1 (-4250 3275)(-4250 3225);
WIRE 16 -1 (-4425 3225)(-4250 3225);
WIRE 16 -1 (-4250 3325)(-4250 3275);
WIRE 16 -1 (-4425 3275)(-4250 3275);
WIRE 16 -1 (-4250 3375)(-4250 3325);
WIRE 16 -1 (-4425 3325)(-4250 3325);
WIRE 16 -1 (-4250 3425)(-4250 3375);
WIRE 16 -1 (-4425 3375)(-4250 3375);
WIRE 16 -1 (-4250 3475)(-4250 3425);
WIRE 16 -1 (-4425 3425)(-4250 3425);
WIRE 16 -1 (-4250 3525)(-4250 3475);
WIRE 16 -1 (-4425 3475)(-4250 3475);
WIRE 16 -1 (-4250 3575)(-4250 3525);
WIRE 16 -1 (-4425 3525)(-4250 3525);
WIRE 16 -1 (-4250 3625)(-4250 3575);
WIRE 16 -1 (-4425 3575)(-4250 3575);
WIRE 16 -1 (-4250 3675)(-4250 3625);
WIRE 16 -1 (-4425 3625)(-4250 3625);
WIRE 16 -1 (-4250 3725)(-4250 3675);
WIRE 16 -1 (-4425 3675)(-4250 3675);
WIRE 16 -1 (-4250 3775)(-4250 3725);
WIRE 16 -1 (-4425 3725)(-4250 3725);
WIRE 16 -1 (-4250 3825)(-4250 3775);
WIRE 16 -1 (-4425 3775)(-4250 3775);
WIRE 16 -1 (-4250 3875)(-4250 3825);
WIRE 16 -1 (-4425 3825)(-4250 3825);
WIRE 16 -1 (-4250 3925)(-4250 3875);
WIRE 16 -1 (-4425 3875)(-4250 3875);
WIRE 16 -1 (-4250 3975)(-4250 3925);
WIRE 16 -1 (-4425 3925)(-4250 3925);
WIRE 16 -1 (-4250 4025)(-4250 3975);
WIRE 16 -1 (-4425 3975)(-4250 3975);
WIRE 16 -1 (-4250 4075)(-4250 4025);
WIRE 16 -1 (-4425 4025)(-4250 4025);
WIRE 16 -1 (-4250 4125)(-4250 4075);
WIRE 16 -1 (-4425 4075)(-4250 4075);
WIRE 16 -1 (-4250 4175)(-4250 4125);
WIRE 16 -1 (-4425 4125)(-4250 4125);
WIRE 16 -1 (-4250 4225)(-4250 4175);
WIRE 16 -1 (-4425 4175)(-4250 4175);
WIRE 16 -1 (-4250 4275)(-4250 4225);
WIRE 16 -1 (-4425 4225)(-4250 4225);
WIRE 16 -1 (-4250 4325)(-4250 4275);
WIRE 16 -1 (-4425 4275)(-4250 4275);
WIRE 16 -1 (-4250 4375)(-4250 4325);
WIRE 16 -1 (-4425 4325)(-4250 4325);
WIRE 16 -1 (-4250 4425)(-4250 4375);
WIRE 16 -1 (-4425 4375)(-4250 4375);
WIRE 16 -1 (-4250 4475)(-4250 4425);
WIRE 16 -1 (-4425 4425)(-4250 4425);
WIRE 16 -1 (-4250 4525)(-4250 4475);
WIRE 16 -1 (-4425 4475)(-4250 4475);
WIRE 16 -1 (-4250 4575)(-4250 4525);
WIRE 16 -1 (-4425 4525)(-4250 4525);
WIRE 16 -1 (-4250 4625)(-4250 4575);
WIRE 16 -1 (-4425 4575)(-4250 4575);
WIRE 16 -1 (-4250 4625)(-4425 4625);
WIRE 16 -1 (-3950 675)(-3950 550);
WIRE 16 -1 (-3950 725)(-3950 675);
WIRE 16 -1 (-3950 675)(-3800 675);
WIRE 16 -1 (-3950 775)(-3950 725);
WIRE 16 -1 (-3800 725)(-3950 725);
WIRE 16 -1 (-3950 825)(-3950 775);
WIRE 16 -1 (-3800 775)(-3950 775);
WIRE 16 -1 (-3950 875)(-3950 825);
WIRE 16 -1 (-3800 825)(-3950 825);
WIRE 16 -1 (-3950 925)(-3950 875);
WIRE 16 -1 (-3800 875)(-3950 875);
WIRE 16 -1 (-3950 975)(-3950 925);
WIRE 16 -1 (-3800 925)(-3950 925);
WIRE 16 -1 (-3950 1025)(-3950 975);
WIRE 16 -1 (-3800 975)(-3950 975);
WIRE 16 -1 (-3950 1075)(-3950 1025);
WIRE 16 -1 (-3800 1025)(-3950 1025);
WIRE 16 -1 (-3950 1125)(-3950 1075);
WIRE 16 -1 (-3800 1075)(-3950 1075);
WIRE 16 -1 (-3950 1175)(-3950 1125);
WIRE 16 -1 (-3800 1125)(-3950 1125);
WIRE 16 -1 (-3950 1225)(-3950 1175);
WIRE 16 -1 (-3800 1175)(-3950 1175);
WIRE 16 -1 (-3950 1275)(-3950 1225);
WIRE 16 -1 (-3800 1225)(-3950 1225);
WIRE 16 -1 (-3950 1325)(-3950 1275);
WIRE 16 -1 (-3800 1275)(-3950 1275);
WIRE 16 -1 (-3950 1375)(-3950 1325);
WIRE 16 -1 (-3800 1325)(-3950 1325);
WIRE 16 -1 (-3950 1425)(-3950 1375);
WIRE 16 -1 (-3800 1375)(-3950 1375);
WIRE 16 -1 (-3950 1475)(-3950 1425);
WIRE 16 -1 (-3800 1425)(-3950 1425);
WIRE 16 -1 (-3950 1525)(-3950 1475);
WIRE 16 -1 (-3800 1475)(-3950 1475);
WIRE 16 -1 (-3950 1575)(-3950 1525);
WIRE 16 -1 (-3800 1525)(-3950 1525);
WIRE 16 -1 (-3950 1625)(-3950 1575);
WIRE 16 -1 (-3800 1575)(-3950 1575);
WIRE 16 -1 (-3950 1675)(-3950 1625);
WIRE 16 -1 (-3800 1625)(-3950 1625);
WIRE 16 -1 (-3950 1725)(-3950 1675);
WIRE 16 -1 (-3800 1675)(-3950 1675);
WIRE 16 -1 (-3950 1775)(-3950 1725);
WIRE 16 -1 (-3800 1725)(-3950 1725);
WIRE 16 -1 (-3950 1825)(-3950 1775);
WIRE 16 -1 (-3800 1775)(-3950 1775);
WIRE 16 -1 (-3950 1875)(-3950 1825);
WIRE 16 -1 (-3800 1825)(-3950 1825);
WIRE 16 -1 (-3950 1925)(-3950 1875);
WIRE 16 -1 (-3800 1875)(-3950 1875);
WIRE 16 -1 (-3950 1975)(-3950 1925);
WIRE 16 -1 (-3800 1925)(-3950 1925);
WIRE 16 -1 (-3950 2025)(-3950 1975);
WIRE 16 -1 (-3800 1975)(-3950 1975);
WIRE 16 -1 (-3950 2075)(-3950 2025);
WIRE 16 -1 (-3800 2025)(-3950 2025);
WIRE 16 -1 (-3950 2125)(-3950 2075);
WIRE 16 -1 (-3800 2075)(-3950 2075);
WIRE 16 -1 (-3950 2175)(-3950 2125);
WIRE 16 -1 (-3800 2125)(-3950 2125);
WIRE 16 -1 (-3950 2225)(-3950 2175);
WIRE 16 -1 (-3800 2175)(-3950 2175);
WIRE 16 -1 (-3950 2275)(-3950 2225);
WIRE 16 -1 (-3800 2225)(-3950 2225);
WIRE 16 -1 (-3950 2325)(-3950 2275);
WIRE 16 -1 (-3800 2275)(-3950 2275);
WIRE 16 -1 (-3950 2375)(-3950 2325);
WIRE 16 -1 (-3800 2325)(-3950 2325);
WIRE 16 -1 (-3950 2425)(-3950 2375);
WIRE 16 -1 (-3800 2375)(-3950 2375);
WIRE 16 -1 (-3950 2475)(-3950 2425);
WIRE 16 -1 (-3800 2425)(-3950 2425);
WIRE 16 -1 (-3950 2525)(-3950 2475);
WIRE 16 -1 (-3800 2475)(-3950 2475);
WIRE 16 -1 (-3950 2575)(-3950 2525);
WIRE 16 -1 (-3800 2525)(-3950 2525);
WIRE 16 -1 (-3950 2625)(-3950 2575);
WIRE 16 -1 (-3800 2575)(-3950 2575);
WIRE 16 -1 (-3950 2675)(-3950 2625);
WIRE 16 -1 (-3800 2625)(-3950 2625);
WIRE 16 -1 (-3950 2725)(-3950 2675);
WIRE 16 -1 (-3800 2675)(-3950 2675);
WIRE 16 -1 (-3950 2775)(-3950 2725);
WIRE 16 -1 (-3800 2725)(-3950 2725);
WIRE 16 -1 (-3950 2825)(-3950 2775);
WIRE 16 -1 (-3800 2775)(-3950 2775);
WIRE 16 -1 (-3950 2875)(-3950 2825);
WIRE 16 -1 (-3800 2825)(-3950 2825);
WIRE 16 -1 (-3950 2925)(-3950 2875);
WIRE 16 -1 (-3800 2875)(-3950 2875);
WIRE 16 -1 (-3950 2975)(-3950 2925);
WIRE 16 -1 (-3800 2925)(-3950 2925);
WIRE 16 -1 (-3950 3025)(-3950 2975);
WIRE 16 -1 (-3800 2975)(-3950 2975);
WIRE 16 -1 (-3950 3075)(-3950 3025);
WIRE 16 -1 (-3800 3025)(-3950 3025);
WIRE 16 -1 (-3950 3125)(-3950 3075);
WIRE 16 -1 (-3800 3075)(-3950 3075);
WIRE 16 -1 (-3950 3175)(-3950 3125);
WIRE 16 -1 (-3800 3125)(-3950 3125);
WIRE 16 -1 (-3950 3225)(-3950 3175);
WIRE 16 -1 (-3800 3175)(-3950 3175);
WIRE 16 -1 (-3950 3275)(-3950 3225);
WIRE 16 -1 (-3800 3225)(-3950 3225);
WIRE 16 -1 (-3950 3325)(-3950 3275);
WIRE 16 -1 (-3800 3275)(-3950 3275);
WIRE 16 -1 (-3950 3375)(-3950 3325);
WIRE 16 -1 (-3800 3325)(-3950 3325);
WIRE 16 -1 (-3950 3425)(-3950 3375);
WIRE 16 -1 (-3800 3375)(-3950 3375);
WIRE 16 -1 (-3950 3475)(-3950 3425);
WIRE 16 -1 (-3800 3425)(-3950 3425);
WIRE 16 -1 (-3950 3525)(-3950 3475);
WIRE 16 -1 (-3800 3475)(-3950 3475);
WIRE 16 -1 (-3950 3575)(-3950 3525);
WIRE 16 -1 (-3800 3525)(-3950 3525);
WIRE 16 -1 (-3950 3625)(-3950 3575);
WIRE 16 -1 (-3800 3575)(-3950 3575);
WIRE 16 -1 (-3950 3675)(-3950 3625);
WIRE 16 -1 (-3800 3625)(-3950 3625);
WIRE 16 -1 (-3950 3725)(-3950 3675);
WIRE 16 -1 (-3800 3675)(-3950 3675);
WIRE 16 -1 (-3950 3775)(-3950 3725);
WIRE 16 -1 (-3800 3725)(-3950 3725);
WIRE 16 -1 (-3950 3825)(-3950 3775);
WIRE 16 -1 (-3800 3775)(-3950 3775);
WIRE 16 -1 (-3950 3875)(-3950 3825);
WIRE 16 -1 (-3800 3825)(-3950 3825);
WIRE 16 -1 (-3950 3925)(-3950 3875);
WIRE 16 -1 (-3800 3875)(-3950 3875);
WIRE 16 -1 (-3950 3975)(-3950 3925);
WIRE 16 -1 (-3800 3925)(-3950 3925);
WIRE 16 -1 (-3950 4025)(-3950 3975);
WIRE 16 -1 (-3800 3975)(-3950 3975);
WIRE 16 -1 (-3950 4075)(-3950 4025);
WIRE 16 -1 (-3800 4025)(-3950 4025);
WIRE 16 -1 (-3950 4125)(-3950 4075);
WIRE 16 -1 (-3800 4075)(-3950 4075);
WIRE 16 -1 (-3950 4175)(-3950 4125);
WIRE 16 -1 (-3800 4125)(-3950 4125);
WIRE 16 -1 (-3950 4225)(-3950 4175);
WIRE 16 -1 (-3800 4175)(-3950 4175);
WIRE 16 -1 (-3950 4275)(-3950 4225);
WIRE 16 -1 (-3800 4225)(-3950 4225);
WIRE 16 -1 (-3950 4325)(-3950 4275);
WIRE 16 -1 (-3800 4275)(-3950 4275);
WIRE 16 -1 (-3950 4375)(-3950 4325);
WIRE 16 -1 (-3800 4325)(-3950 4325);
WIRE 16 -1 (-3950 4425)(-3950 4375);
WIRE 16 -1 (-3800 4375)(-3950 4375);
WIRE 16 -1 (-3950 4475)(-3950 4425);
WIRE 16 -1 (-3800 4425)(-3950 4425);
WIRE 16 -1 (-3950 4525)(-3950 4475);
WIRE 16 -1 (-3800 4475)(-3950 4475);
WIRE 16 -1 (-3950 4575)(-3950 4525);
WIRE 16 -1 (-3800 4525)(-3950 4525);
WIRE 16 -1 (-3950 4625)(-3950 4575);
WIRE 16 -1 (-3800 4575)(-3950 4575);
WIRE 16 -1 (-3950 4625)(-3800 4625);
DOT 1 (-7625 4200);
DOT 1 (-7625 4350);
DOT 1 (-3950 3925);
DOT 1 (-5775 4575);
DOT 1 (-5775 2875);
DOT 1 (-3950 4525);
DOT 1 (-4250 4475);
DOT 1 (-5775 4475);
DOT 1 (-6100 3300);
DOT 1 (-6100 2300);
DOT 1 (-6100 2250);
DOT 1 (-6100 1550);
DOT 1 (-6100 1500);
DOT 1 (-5775 4525);
DOT 1 (-5775 4375);
DOT 1 (-5775 4425);
DOT 1 (-6100 3550);
DOT 1 (-5775 3425);
DOT 1 (-7625 900);
DOT 1 (-2025 1850);
DOT 1 (-6100 1600);
DOT 1 (-4250 2525);
DOT 1 (-6100 1300);
DOT 1 (-5775 1175);
DOT 1 (-3950 3575);
DOT 1 (-5775 2425);
DOT 1 (-500 3000);
DOT 1 (-7625 1300);
DOT 1 (-6100 1100);
DOT 1 (-6100 1150);
DOT 1 (-6100 3500);
DOT 1 (-2425 3875);
DOT 1 (-2425 3825);
DOT 1 (-2425 3675);
DOT 1 (-3950 3325);
DOT 1 (-7625 2600);
DOT 1 (-500 3150);
DOT 1 (-500 4550);
DOT 1 (-500 4450);
DOT 1 (-500 4500);
DOT 1 (-500 4400);
DOT 1 (-500 4350);
DOT 1 (-500 4300);
DOT 1 (-500 4250);
DOT 1 (-500 4200);
DOT 1 (-2025 4550);
DOT 1 (-2025 4500);
DOT 1 (-2025 4450);
DOT 1 (-2025 4350);
DOT 1 (-2025 4300);
DOT 1 (-2025 4400);
DOT 1 (-2025 4200);
DOT 1 (-2025 4250);
DOT 1 (-2025 4150);
DOT 1 (-500 4150);
DOT 1 (-500 4100);
DOT 1 (-500 4050);
DOT 1 (-500 4000);
DOT 1 (-500 3950);
DOT 1 (-500 3900);
DOT 1 (-500 3850);
DOT 1 (-500 3800);
DOT 1 (-500 3750);
DOT 1 (-500 3700);
DOT 1 (-500 3650);
DOT 1 (-500 3600);
DOT 1 (-500 3550);
DOT 1 (-500 3500);
DOT 1 (-500 3450);
DOT 1 (-500 3400);
DOT 1 (-500 3350);
DOT 1 (-500 3300);
DOT 1 (-500 3200);
DOT 1 (-500 3250);
DOT 1 (-500 3100);
DOT 1 (-500 3050);
DOT 1 (-500 2950);
DOT 1 (-500 2900);
DOT 1 (-500 2850);
DOT 1 (-500 2800);
DOT 1 (-500 2750);
DOT 1 (-500 2700);
DOT 1 (-500 2650);
DOT 1 (-500 2600);
DOT 1 (-500 2550);
DOT 1 (-500 2500);
DOT 1 (-500 2400);
DOT 1 (-500 2450);
DOT 1 (-500 2350);
DOT 1 (-500 2300);
DOT 1 (-500 2250);
DOT 1 (-500 2200);
DOT 1 (-500 2150);
DOT 1 (-500 2100);
DOT 1 (-500 2050);
DOT 1 (-500 2000);
DOT 1 (-500 1950);
DOT 1 (-500 1900);
DOT 1 (-500 1850);
DOT 1 (-500 1800);
DOT 1 (-500 1750);
DOT 1 (-500 1700);
DOT 1 (-500 1650);
DOT 1 (-500 1600);
DOT 1 (-500 1550);
DOT 1 (-500 1500);
DOT 1 (-500 1450);
DOT 1 (-500 1400);
DOT 1 (-500 1350);
DOT 1 (-500 1300);
DOT 1 (-500 1250);
DOT 1 (-500 1200);
DOT 1 (-500 1150);
DOT 1 (-500 1100);
DOT 1 (-500 1050);
DOT 1 (-500 1000);
DOT 1 (-500 950);
DOT 1 (-500 900);
DOT 1 (-500 850);
DOT 1 (-500 800);
DOT 1 (-500 750);
DOT 1 (-500 700);
DOT 1 (-500 650);
DOT 1 (-2025 4100);
DOT 1 (-2025 4050);
DOT 1 (-2025 3950);
DOT 1 (-2025 4000);
DOT 1 (-2025 3900);
DOT 1 (-2025 3850);
DOT 1 (-2025 3800);
DOT 1 (-2025 3650);
DOT 1 (-2025 3700);
DOT 1 (-2025 3750);
DOT 1 (-2025 3600);
DOT 1 (-2025 3550);
DOT 1 (-2025 3450);
DOT 1 (-2025 3400);
DOT 1 (-2025 3500);
DOT 1 (-2025 3350);
DOT 1 (-2025 3300);
DOT 1 (-2025 3250);
DOT 1 (-2025 3200);
DOT 1 (-2025 3150);
DOT 1 (-2025 3050);
DOT 1 (-2025 3100);
DOT 1 (-2025 3000);
DOT 1 (-2025 2950);
DOT 1 (-2025 2900);
DOT 1 (-2025 2800);
DOT 1 (-2025 2850);
DOT 1 (-2025 2750);
DOT 1 (-2025 2650);
DOT 1 (-2025 2700);
DOT 1 (-2025 2550);
DOT 1 (-2025 2500);
DOT 1 (-2025 2600);
DOT 1 (-2025 2450);
DOT 1 (-2025 2400);
DOT 1 (-2025 2300);
DOT 1 (-2025 2250);
DOT 1 (-2025 2350);
DOT 1 (-2025 2150);
DOT 1 (-2025 2200);
DOT 1 (-2025 2100);
DOT 1 (-2025 2050);
DOT 1 (-2025 2000);
DOT 1 (-2025 1900);
DOT 1 (-2025 1950);
DOT 1 (-2025 1800);
DOT 1 (-2025 1750);
DOT 1 (-2025 1700);
DOT 1 (-2025 1650);
DOT 1 (-2025 1600);
DOT 1 (-2025 1550);
DOT 1 (-2025 1500);
DOT 1 (-2025 1400);
DOT 1 (-2025 1350);
DOT 1 (-2025 1450);
DOT 1 (-2025 1300);
DOT 1 (-2025 1250);
DOT 1 (-2025 1100);
DOT 1 (-2025 1150);
DOT 1 (-2025 1200);
DOT 1 (-2025 1000);
DOT 1 (-2025 1050);
DOT 1 (-2025 950);
DOT 1 (-2025 900);
DOT 1 (-2025 850);
DOT 1 (-2025 750);
DOT 1 (-2025 800);
DOT 1 (-2025 700);
DOT 1 (-2025 650);
DOT 1 (-2425 4575);
DOT 1 (-2425 4525);
DOT 1 (-2425 4425);
DOT 1 (-2425 4475);
DOT 1 (-2425 4275);
DOT 1 (-2425 4325);
DOT 1 (-2425 4375);
DOT 1 (-2425 4175);
DOT 1 (-2425 4225);
DOT 1 (-3950 4575);
DOT 1 (-3950 4425);
DOT 1 (-3950 4475);
DOT 1 (-3950 4275);
DOT 1 (-3950 4325);
DOT 1 (-3950 4375);
DOT 1 (-3950 4175);
DOT 1 (-3950 4225);
DOT 1 (-3950 4125);
DOT 1 (-2425 4125);
DOT 1 (-2425 4075);
DOT 1 (-2425 4025);
DOT 1 (-2425 3925);
DOT 1 (-2425 3975);
DOT 1 (-2425 3775);
DOT 1 (-2425 3625);
DOT 1 (-2425 3725);
DOT 1 (-2425 3575);
DOT 1 (-2425 3525);
DOT 1 (-2425 3375);
DOT 1 (-2425 3475);
DOT 1 (-2425 3425);
DOT 1 (-2425 3325);
DOT 1 (-2425 3275);
DOT 1 (-2425 3225);
DOT 1 (-2425 3175);
DOT 1 (-2425 3125);
DOT 1 (-2425 3025);
DOT 1 (-2425 3075);
DOT 1 (-2425 2975);
DOT 1 (-2425 2925);
DOT 1 (-2425 2875);
DOT 1 (-2425 2775);
DOT 1 (-2425 2825);
DOT 1 (-2425 2725);
DOT 1 (-2425 2675);
DOT 1 (-2425 2625);
DOT 1 (-2425 2475);
DOT 1 (-2425 2525);
DOT 1 (-2425 2575);
DOT 1 (-2425 2425);
DOT 1 (-2425 2375);
DOT 1 (-2425 2225);
DOT 1 (-2425 2275);
DOT 1 (-2425 2325);
DOT 1 (-2425 2125);
DOT 1 (-2425 2175);
DOT 1 (-2425 2075);
DOT 1 (-2425 2025);
DOT 1 (-2425 1975);
DOT 1 (-2425 1875);
DOT 1 (-2425 1925);
DOT 1 (-2425 1825);
DOT 1 (-2425 1775);
DOT 1 (-2425 1725);
DOT 1 (-2425 1675);
DOT 1 (-2425 1625);
DOT 1 (-2425 1575);
DOT 1 (-2425 1475);
DOT 1 (-2425 1525);
DOT 1 (-2425 1325);
DOT 1 (-2425 1425);
DOT 1 (-2425 1375);
DOT 1 (-2425 1275);
DOT 1 (-2425 1225);
DOT 1 (-2425 1075);
DOT 1 (-2425 1125);
DOT 1 (-2425 1175);
DOT 1 (-2425 975);
DOT 1 (-2425 1025);
DOT 1 (-2425 925);
DOT 1 (-2425 875);
DOT 1 (-2425 825);
DOT 1 (-2425 725);
DOT 1 (-2425 775);
DOT 1 (-2425 675);
DOT 1 (-3950 4025);
DOT 1 (-3950 4075);
DOT 1 (-3950 3975);
DOT 1 (-3950 3875);
DOT 1 (-3950 3775);
DOT 1 (-3950 3825);
DOT 1 (-3950 3625);
DOT 1 (-3950 3675);
DOT 1 (-3950 3725);
DOT 1 (-3950 3525);
DOT 1 (-3950 3375);
DOT 1 (-3950 3425);
DOT 1 (-3950 3475);
DOT 1 (-3950 3275);
DOT 1 (-3950 3125);
DOT 1 (-3950 3225);
DOT 1 (-3950 3175);
DOT 1 (-3950 3025);
DOT 1 (-3950 3075);
DOT 1 (-3950 2975);
DOT 1 (-3950 2875);
DOT 1 (-3950 2925);
DOT 1 (-3950 2775);
DOT 1 (-3950 2825);
DOT 1 (-3950 2725);
DOT 1 (-3950 2625);
DOT 1 (-3950 2675);
DOT 1 (-3950 2475);
DOT 1 (-3950 2525);
DOT 1 (-3950 2575);
DOT 1 (-3950 2375);
DOT 1 (-3950 2425);
DOT 1 (-3950 2225);
DOT 1 (-3950 2275);
DOT 1 (-3950 2325);
DOT 1 (-3950 2125);
DOT 1 (-3950 2175);
DOT 1 (-3950 2075);
DOT 1 (-3950 1975);
DOT 1 (-3950 2025);
DOT 1 (-3950 1875);
DOT 1 (-3950 1825);
DOT 1 (-3950 1725);
DOT 1 (-3950 1775);
DOT 1 (-3950 1575);
DOT 1 (-3950 1675);
DOT 1 (-3950 1625);
DOT 1 (-3950 1475);
DOT 1 (-3950 1525);
DOT 1 (-3950 1325);
DOT 1 (-3950 1375);
DOT 1 (-3950 1425);
DOT 1 (-3950 1225);
DOT 1 (-3950 1275);
DOT 1 (-3950 1075);
DOT 1 (-3950 1125);
DOT 1 (-3950 1175);
DOT 1 (-3950 1025);
DOT 1 (-3950 925);
DOT 1 (-3950 825);
DOT 1 (-3950 875);
DOT 1 (-3950 725);
DOT 1 (-3950 775);
DOT 1 (-3950 675);
DOT 1 (-5775 725);
DOT 1 (-5775 675);
DOT 1 (-5775 775);
DOT 1 (-5775 825);
DOT 1 (-5775 875);
DOT 1 (-5775 925);
DOT 1 (-5775 975);
DOT 1 (-5775 1025);
DOT 1 (-5775 1075);
DOT 1 (-5775 1125);
DOT 1 (-5775 1225);
DOT 1 (-5775 1275);
DOT 1 (-5775 1375);
DOT 1 (-5775 1325);
DOT 1 (-5775 1425);
DOT 1 (-5775 1475);
DOT 1 (-5775 1525);
DOT 1 (-5775 1625);
DOT 1 (-5775 1575);
DOT 1 (-5775 1675);
DOT 1 (-5775 1725);
DOT 1 (-5775 1775);
DOT 1 (-5775 1875);
DOT 1 (-5775 1825);
DOT 1 (-5775 1925);
DOT 1 (-5775 1975);
DOT 1 (-5775 2025);
DOT 1 (-5775 2175);
DOT 1 (-5775 2225);
DOT 1 (-5775 2275);
DOT 1 (-5775 2325);
DOT 1 (-5775 2375);
DOT 1 (-5775 2475);
DOT 1 (-5775 2525);
DOT 1 (-5775 2575);
DOT 1 (-5775 2625);
DOT 1 (-5775 2675);
DOT 1 (-5775 2725);
DOT 1 (-5775 2775);
DOT 1 (-5775 2825);
DOT 1 (-5775 2925);
DOT 1 (-5775 3025);
DOT 1 (-5775 2975);
DOT 1 (-5775 3075);
DOT 1 (-5775 3125);
DOT 1 (-5775 3175);
DOT 1 (-5775 3225);
DOT 1 (-5775 3275);
DOT 1 (-5775 3325);
DOT 1 (-5775 3375);
DOT 1 (-5775 3475);
DOT 1 (-5775 3525);
DOT 1 (-5775 3575);
DOT 1 (-5775 3675);
DOT 1 (-5775 3625);
DOT 1 (-5775 3925);
DOT 1 (-5775 3875);
DOT 1 (-5775 3975);
DOT 1 (-5775 4025);
DOT 1 (-5775 4075);
DOT 1 (-4250 675);
DOT 1 (-4250 725);
DOT 1 (-4250 775);
DOT 1 (-4250 825);
DOT 1 (-4250 875);
DOT 1 (-4250 925);
DOT 1 (-4250 975);
DOT 1 (-4250 1025);
DOT 1 (-4250 1075);
DOT 1 (-4250 1125);
DOT 1 (-4250 1175);
DOT 1 (-4250 1225);
DOT 1 (-4250 1275);
DOT 1 (-4250 1325);
DOT 1 (-4250 1375);
DOT 1 (-4250 1475);
DOT 1 (-4250 1525);
DOT 1 (-4250 1625);
DOT 1 (-4250 1575);
DOT 1 (-4250 1675);
DOT 1 (-4250 1775);
DOT 1 (-4250 1825);
DOT 1 (-4250 1875);
DOT 1 (-4250 1925);
DOT 1 (-4250 1975);
DOT 1 (-4250 2025);
DOT 1 (-4250 2075);
DOT 1 (-4250 2125);
DOT 1 (-4250 2175);
DOT 1 (-4250 2225);
DOT 1 (-4250 2275);
DOT 1 (-4250 2325);
DOT 1 (-4250 2375);
DOT 1 (-4250 2425);
DOT 1 (-4250 2475);
DOT 1 (-4250 2575);
DOT 1 (-4250 2625);
DOT 1 (-4250 2675);
DOT 1 (-4250 2725);
DOT 1 (-4250 2775);
DOT 1 (-4250 2825);
DOT 1 (-4250 2875);
DOT 1 (-4250 2925);
DOT 1 (-4250 2975);
DOT 1 (-4250 3025);
DOT 1 (-4250 3075);
DOT 1 (-4250 3125);
DOT 1 (-4250 3175);
DOT 1 (-4250 3225);
DOT 1 (-4250 3275);
DOT 1 (-4250 3325);
DOT 1 (-4250 3375);
DOT 1 (-4250 3425);
DOT 1 (-4250 3475);
DOT 1 (-4250 3525);
DOT 1 (-4250 3575);
DOT 1 (-4250 3675);
DOT 1 (-4250 3625);
DOT 1 (-4250 3725);
DOT 1 (-4250 3825);
DOT 1 (-4250 3925);
DOT 1 (-4250 3875);
DOT 1 (-4250 3975);
DOT 1 (-4250 4025);
DOT 1 (-4250 4075);
DOT 1 (-5775 4175);
DOT 1 (-5775 4125);
DOT 1 (-5775 4225);
DOT 1 (-5775 4275);
DOT 1 (-4250 4175);
DOT 1 (-4250 4125);
DOT 1 (-4250 4225);
DOT 1 (-4250 4275);
DOT 1 (-4250 4325);
DOT 1 (-4250 4375);
DOT 1 (-4250 4425);
DOT 1 (-4250 4525);
DOT 1 (-4250 4575);
DOT 1 (-7625 650);
DOT 1 (-7625 700);
DOT 1 (-7625 750);
DOT 1 (-7625 800);
DOT 1 (-7625 850);
DOT 1 (-7625 950);
DOT 1 (-7625 1000);
DOT 1 (-7625 1050);
DOT 1 (-7625 1100);
DOT 1 (-7625 1150);
DOT 1 (-7625 1200);
DOT 1 (-7625 1250);
DOT 1 (-7625 1350);
DOT 1 (-7625 1400);
DOT 1 (-7625 1450);
DOT 1 (-7625 1500);
DOT 1 (-7625 1550);
DOT 1 (-7625 1600);
DOT 1 (-7625 1650);
DOT 1 (-7625 1700);
DOT 1 (-7625 1750);
DOT 1 (-7625 1800);
DOT 1 (-7625 1850);
DOT 1 (-7625 1900);
DOT 1 (-7625 1950);
DOT 1 (-7625 2000);
DOT 1 (-7625 2050);
DOT 1 (-7625 2100);
DOT 1 (-7625 2150);
DOT 1 (-7625 2200);
DOT 1 (-7625 2250);
DOT 1 (-7625 2300);
DOT 1 (-7625 2350);
DOT 1 (-7625 2400);
DOT 1 (-7625 2450);
DOT 1 (-7625 2500);
DOT 1 (-7625 2550);
DOT 1 (-7625 2650);
DOT 1 (-7625 2700);
DOT 1 (-7625 2750);
DOT 1 (-7625 2800);
DOT 1 (-7625 2850);
DOT 1 (-7625 2900);
DOT 1 (-7625 2950);
DOT 1 (-7625 3000);
DOT 1 (-7625 3050);
DOT 1 (-7625 3150);
DOT 1 (-7625 3100);
DOT 1 (-7625 3200);
DOT 1 (-7625 3250);
DOT 1 (-7625 3300);
DOT 1 (-7625 3350);
DOT 1 (-7625 3400);
DOT 1 (-7625 3450);
DOT 1 (-7625 3500);
DOT 1 (-7625 3550);
DOT 1 (-7625 3600);
DOT 1 (-7625 3650);
DOT 1 (-7625 3700);
DOT 1 (-7625 3750);
DOT 1 (-7625 3800);
DOT 1 (-7625 3850);
DOT 1 (-7625 3900);
DOT 1 (-7625 3950);
DOT 1 (-7625 4000);
DOT 1 (-7625 4050);
DOT 1 (-6100 650);
DOT 1 (-6100 700);
DOT 1 (-6100 750);
DOT 1 (-6100 800);
DOT 1 (-6100 850);
DOT 1 (-6100 900);
DOT 1 (-6100 950);
DOT 1 (-6100 1000);
DOT 1 (-6100 1050);
DOT 1 (-6100 1200);
DOT 1 (-6100 1250);
DOT 1 (-6100 1350);
DOT 1 (-6100 1400);
DOT 1 (-6100 1450);
DOT 1 (-6100 1650);
DOT 1 (-6100 1700);
DOT 1 (-6100 1750);
DOT 1 (-6100 1800);
DOT 1 (-6100 1850);
DOT 1 (-6100 1900);
DOT 1 (-6100 1950);
DOT 1 (-6100 2000);
DOT 1 (-6100 2050);
DOT 1 (-6100 2100);
DOT 1 (-6100 2150);
DOT 1 (-6100 2200);
DOT 1 (-6100 2350);
DOT 1 (-6100 2400);
DOT 1 (-6100 2450);
DOT 1 (-6100 2500);
DOT 1 (-6100 2550);
DOT 1 (-6100 2600);
DOT 1 (-6100 2650);
DOT 1 (-6100 2700);
DOT 1 (-6100 2750);
DOT 1 (-6100 2800);
DOT 1 (-6100 2850);
DOT 1 (-6100 2900);
DOT 1 (-6100 2950);
DOT 1 (-6100 3000);
DOT 1 (-6100 3050);
DOT 1 (-6100 3100);
DOT 1 (-6100 3200);
DOT 1 (-6100 3250);
DOT 1 (-6100 3350);
DOT 1 (-6100 3400);
DOT 1 (-6100 3450);
DOT 1 (-6100 3750);
DOT 1 (-6100 3800);
DOT 1 (-6100 3850);
DOT 1 (-6100 3900);
DOT 1 (-6100 3950);
DOT 1 (-6100 4000);
DOT 1 (-6100 4050);
DOT 1 (-6100 4100);
DOT 1 (-7625 4100);
DOT 1 (-7625 4150);
DOT 1 (-7625 4250);
DOT 1 (-7625 4300);
DOT 1 (-7625 4400);
DOT 1 (-7625 4450);
DOT 1 (-7625 4500);
DOT 1 (-7625 4550);
DOT 1 (-6100 4150);
DOT 1 (-6100 4200);
DOT 1 (-6100 4250);
DOT 1 (-6100 4300);
DOT 1 (-6100 4350);
DOT 1 (-6100 4400);
DOT 1 (-6100 4550);
DOT 1 (-5775 2075);
DOT 1 (-6100 3600);
DOT 1 (-6100 3650);
DOT 1 (-6100 3700);
DOT 1 (-5775 4325);
DOT 1 (-6100 3150);
DOT 1 (-6100 4500);
DOT 1 (-6100 4450);
DOT 1 (-5775 2125);
DOT 1 (-5775 3825);
DOT 1 (-5775 3775);
DOT 1 (-5775 3725);
DOT 1 (-4250 1725);
DOT 1 (-4250 1425);
DOT 1 (-4250 3775);
DOT 1 (-3950 1925);
DOT 1 (-3950 975);
FORCENOTE
ROOM=CPU1
(-8025 325) 0;
DISPLAY LEFT (-8025 325);
DISPLAY 1.723404 (-8025 325);
PAINT PURPLE (-8025 325);
FORCENOTE
BOM_COST=PROC_SOCKET
(-8025 200) 0;
DISPLAY LEFT (-8025 200);
DISPLAY 1.723404 (-8025 200);
PAINT PURPLE (-8025 200);
QUIT
